PARTS LIST

83.01921.S70       LED1608AKH40                BLED1
078.10321.02S1     C0201H13                    C1
078.10321.02S1     C0201H13                    C2
078.10321.02S1     C0201H13                    C3
078.10321.02S1     C0201H13                    C4
078.10321.02S1     C0201H13                    C5
078.10321.02S1     C0201H13                    C6
078.10321.02S1     C0201H13                    C7
078.10321.02S1     C0201H13                    C8
078.10321.02S1     C0201H13                    C9
078.10321.02S1     C0201H13                    C10
078.10321.02S1     C0201H13                    C11
078.10321.02S1     C0201H13                    C12
078.10321.02S1     C0201H13                    C13
078.10321.02S1     C0201H13                    C14
078.10321.02S1     C0201H13                    C15
078.10321.02S1     C0201H13                    C16
078.10321.02S1     C0201H13                    C17
078.10321.02S1     C0201H13                    C18
078.10321.02S1     C0201H13                    C19
078.10321.02S1     C0201H13                    C20
078.10321.02S1     C0201H13                    C21
078.10321.02S1     C0201H13                    C22
078.10321.02S1     C0201H13                    C23
078.10321.02S1     C0201H13                    C24
078.10321.02S1     C0201H13                    C25
078.10321.02S1     C0201H13                    C26
078.10321.02S1     C0201H13                    C27
078.10321.02S1     C0201H13                    C28
078.10321.02S1     C0201H13                    C29
078.10321.02S1     C0201H13                    C30
078.10321.02S1     C0201H13                    C31
078.10321.02S1     C0201H13                    C32
078.10321.02S1     C0201H13                    C33
078.10321.02S1     C0201H13                    C34
078.10321.02S1     C0201H13                    C35
078.10321.02S1     C0201H13                    C36
078.10321.02S1     C0201H13                    C37
078.10321.02S1     C0201H13                    C38
078.10321.02S1     C0201H13                    C39
078.10321.02S1     C0201H13                    C40
078.10321.02S1     C0201H13                    C41
078.10321.02S1     C0201H13                    C42
078.10321.02S1     C0201H13                    C43
078.10321.02S1     C0201H13                    C44
078.10321.02S1     C0201H13                    C45
078.10321.02S1     C0201H13                    C46
078.10321.02S1     C0201H13                    C47
078.10321.02S1     C0201H13                    C48
078.10321.02S1     C0201H13                    C49
078.10321.02S1     C0201H13                    C50
078.10321.02S1     C0201H13                    C51
078.10321.02S1     C0201H13                    C52
078.10321.02S1     C0201H13                    C53
078.10321.02S1     C0201H13                    C54
078.10321.02S1     C0201H13                    C55
078.10321.02S1     C0201H13                    C56
078.10321.02S1     C0201H13                    C57
078.10321.02S1     C0201H13                    C58
078.10321.02S1     C0201H13                    C59
078.10321.02S1     C0201H13                    C60
078.10321.02S1     C0201H13                    C61
078.10321.02S1     C0201H13                    C62
078.10321.02S1     C0201H13                    C63
078.10321.02S1     C0201H13                    C64
078.10321.02S1     C0201H13                    C65
078.10321.02S1     C0201H13                    C66
078.10321.02S1     C0201H13                    C67
078.10321.02S1     C0201H13                    C68
078.10321.02S1     C0201H13                    C69
078.10321.02S1     C0201H13                    C70
078.10321.02S1     C0201H13                    C71
078.10321.02S1     C0201H13                    C72
078.10321.02S1     C0201H13                    C73
078.10321.02S1     C0201H13                    C74
078.10321.02S1     C0201H13                    C75
078.10321.02S1     C0201H13                    C76
078.10321.02S1     C0201H13                    C77
078.10321.02S1     C0201H13                    C78
078.10321.02S1     C0201H13                    C79
078.10321.02S1     C0201H13                    C80
078.10321.02S1     C0201H13                    C81
078.10321.02S1     C0201H13                    C82
078.10321.02S1     C0201H13                    C83
078.10321.02S1     C0201H13                    C84
078.10321.02S1     C0201H13                    C85
078.10321.02S1     C0201H13                    C86
078.10321.02S1     C0201H13                    C87
078.10321.02S1     C0201H13                    C88
078.10321.02S1     C0201H13                    C89
078.10321.02S1     C0201H13                    C90
078.10321.02S1     C0201H13                    C91
078.10321.02S1     C0201H13                    C92
078.10321.02S1     C0201H13                    C93
078.10321.02S1     C0201H13                    C94
078.10321.02S1     C0201H13                    C95
078.10321.02S1     C0201H13                    C96
78.10421.2FL       C402H22                     C97
78.10421.2FL       C402H22                     C98
78.10421.2FL       C402H22                     C101
78.10421.2FL       C402H22                     C104
78.22522.21L       C805H54                     C108
78.10620.21L       C805H58                     C109
78.15034.1FL       C402H22                     C110
78.15034.1FL       C402H22                     C111
78.10421.2FL       C402H22                     C112
78.10322.2FL       C402H22                     C113
78.10421.2FL       C402H22                     C114
78.22522.21L       C805H54                     C115
78.10421.2FL       C402H22                     C116
78.10421.2FL       C402H22                     C117
78.10610.5FL       C402-TO0D2H28               C118
78.10610.5FL       C402-TO0D2H28               C119
78.10610.5FL       C402-TO0D2H28               C120
78.10610.5FL       C402-TO0D2H28               C121
78.10610.5FL       C402-TO0D2H28               C122
78.10222.20L       C0201H13                    C123
78.10222.20L       C0201H13                    C124
78.10222.20L       C0201H13                    C125
78.10222.20L       C0201H13                    C126
78.10222.20L       C0201H13                    C127
78.10420.50L       C0201H13                    C128
78.10420.50L       C0201H13                    C129
78.10420.50L       C0201H13                    C130
78.10420.50L       C0201H13                    C131
78.10420.50L       C0201H13                    C132
78.10420.50L       C0201H13                    C133
78.10420.50L       C0201H13                    C134
78.10420.50L       C0201H13                    C135
78.10420.50L       C0201H13                    C136
78.10420.50L       C0201H13                    C137
78.10420.50L       C0201H13                    C138
78.10420.50L       C0201H13                    C139
78.10420.50L       C0201H13                    C140
78.10420.50L       C0201H13                    C141
78.10420.50L       C0201H13                    C142
78.10420.50L       C0201H13                    C143
78.10420.50L       C0201H13                    C144
78.10420.50L       C0201H13                    C145
78.10420.50L       C0201H13                    C146
78.10420.50L       C0201H13                    C147
78.10420.50L       C0201H13                    C148
78.10420.50L       C0201H13                    C149
78.10420.50L       C0201H13                    C150
78.10420.50L       C0201H13                    C151
78.10420.50L       C0201H13                    C152
78.10420.50L       C0201H13                    C153
78.10420.50L       C0201H13                    C154
78.10420.50L       C0201H13                    C155
78.10420.50L       C0201H13                    C156
78.10420.50L       C0201H13                    C157
78.10420.50L       C0201H13                    C158
78.10420.50L       C0201H13                    C159
78.10420.50L       C0201H13                    C160
78.10420.50L       C0201H13                    C161
78.10420.50L       C0201H13                    C162
78.10420.50L       C0201H13                    C163
78.10420.50L       C0201H13                    C164
78.10420.50L       C0201H13                    C165
78.10420.50L       C0201H13                    C166
78.10420.50L       C0201H13                    C167
78.10420.50L       C0201H13                    C168
78.10420.50L       C0201H13                    C169
78.10420.50L       C0201H13                    C170
78.10420.50L       C0201H13                    C171
78.10420.50L       C0201H13                    C172
78.10420.50L       C0201H13                    C173
78.10420.50L       C0201H13                    C174
78.10420.50L       C0201H13                    C175
78.10420.50L       C0201H13                    C176
78.10420.50L       C0201H13                    C177
78.10420.50L       C0201H13                    C178
78.10420.50L       C0201H13                    C179
78.10420.50L       C0201H13                    C180
78.10420.50L       C0201H13                    C181
78.10420.50L       C0201H13                    C182
78.10610.5FL       C402-TO0D2H28               C183
78.10610.5FL       C402-TO0D2H28               C184
78.10610.5FL       C402-TO0D2H28               C185
78.10610.5FL       C402-TO0D2H28               C186
78.10222.20L       C0201H13                    C187
78.10222.20L       C0201H13                    C188
78.10222.20L       C0201H13                    C189
78.10222.20L       C0201H13                    C190
078.22610.08B1     C603H40                     C192
78.10610.5FL       C402-TO0D2H28               C193
78.10510.5SL       C0201H14                    C194
78.10420.50L       C0201H13                    C195
078.22610.08B1     C603H40                     C196
78.10610.5FL       C402-TO0D2H28               C197
78.10510.5SL       C0201H14                    C198
78.10420.50L       C0201H13                    C199
078.22610.08B1     C603H40                     C200
78.10610.5FL       C402-TO0D2H28               C201
78.10510.5SL       C0201H14                    C202
78.10420.50L       C0201H13                    C203
078.22610.08B1     C603H40                     C204
78.10610.5FL       C402-TO0D2H28               C205
78.10510.5SL       C0201H14                    C206
78.10420.50L       C0201H13                    C207
078.22610.08B1     C603H40                     C208
78.10610.5FL       C402-TO0D2H28               C209
78.10510.5SL       C0201H14                    C210
78.10420.50L       C0201H13                    C211
78.10421.2FL       C402H22                     C212
078.10521.08F1     C402-TO0D2H24               C214
78.10421.2FL       C402H22                     C215
78.10421.2FL       C402H22                     C216
78.10421.2FL       C402H22                     C217
78.10421.2FL       C402H22                     C218
78.10421.2FL       C402H22                     C219
78.10421.2FL       C402H22                     C220
78.10421.2FL       C402H22                     C221
78.10421.2FL       C402H22                     C222
78.10421.2FL       C402H22                     C223
78.10421.2FL       C402H22                     C224
78.10421.2FL       C402H22                     C225
78.10421.2FL       C402H22                     C226
78.10710.52L       C1206H71                    C227
078.22610.08B1     C603H40                     C228
78.10510.5SL       C0201H14                    C229
78.10420.50L       C0201H13                    C230
78.10420.50L       C0201H13                    C231
78.10420.50L       C0201H13                    C232
78.10420.50L       C0201H13                    C233
78.10710.52L       C1206H71                    C234
078.22610.08B1     C603H40                     C235
78.10510.5SL       C0201H14                    C236
78.10420.50L       C0201H13                    C237
78.10420.50L       C0201H13                    C238
78.10420.50L       C0201H13                    C239
78.10420.50L       C0201H13                    C240
78.10710.52L       C1206H71                    C241
078.22610.08B1     C603H40                     C242
78.10510.5SL       C0201H14                    C243
78.10420.50L       C0201H13                    C244
78.10420.50L       C0201H13                    C245
78.10420.50L       C0201H13                    C246
78.10420.50L       C0201H13                    C247
78.10710.52L       C1206H71                    C248
078.22610.08B1     C603H40                     C249
78.10510.5SL       C0201H14                    C250
78.10420.50L       C0201H13                    C251
78.10420.50L       C0201H13                    C252
78.10420.50L       C0201H13                    C253
78.10420.50L       C0201H13                    C254
78.10710.52L       C1206H71                    C255
078.22610.08B1     C603H40                     C256
78.10510.5SL       C0201H14                    C257
78.10420.50L       C0201H13                    C258
78.10420.50L       C0201H13                    C259
78.10420.50L       C0201H13                    C260
78.10420.50L       C0201H13                    C261
78.10710.52L       C1206H71                    C262
078.22610.08B1     C603H40                     C263
78.10510.5SL       C0201H14                    C264
78.10420.50L       C0201H13                    C265
78.10420.50L       C0201H13                    C266
78.10420.50L       C0201H13                    C267
78.10420.50L       C0201H13                    C268
78.10420.50L       C0201H13                    C269
78.10710.52L       C1206H71                    C270
78.10420.50L       C0201H13                    C271
78.10420.50L       C0201H13                    C272
78.10420.50L       C0201H13                    C273
78.10510.5SL       C0201H14                    C274
078.22610.08B1     C603H40                     C275
78.10420.50L       C0201H13                    C276
78.10710.52L       C1206H71                    C277
78.10420.50L       C0201H13                    C278
78.10420.50L       C0201H13                    C279
78.10420.50L       C0201H13                    C280
78.10510.5SL       C0201H14                    C281
78.10420.50L       C0201H13                    C282
78.10710.52L       C1206H71                    C283
78.10420.50L       C0201H13                    C284
78.10420.50L       C0201H13                    C285
78.10420.50L       C0201H13                    C286
78.10510.5SL       C0201H14                    C287
078.22610.08B1     C603H40                     C288
78.10420.50L       C0201H13                    C289
78.10710.52L       C1206H71                    C290
78.10420.50L       C0201H13                    C291
78.10420.50L       C0201H13                    C292
78.10420.50L       C0201H13                    C293
78.10510.5SL       C0201H14                    C294
078.22610.08B1     C603H40                     C295
078.22610.08B1     C603H40                     C296
78.10420.50L       C0201H13                    C297
78.10710.52L       C1206H71                    C298
78.10420.50L       C0201H13                    C299
78.10420.50L       C0201H13                    C300
78.10420.50L       C0201H13                    C301
78.10510.5SL       C0201H14                    C302
078.22610.08B1     C603H40                     C303
78.10420.50L       C0201H13                    C304
78.10710.52L       C1206H71                    C305
78.10420.50L       C0201H13                    C306
78.10420.50L       C0201H13                    C307
78.10420.50L       C0201H13                    C308
78.10510.5SL       C0201H14                    C309
078.22610.08B1     C603H40                     C310
78.22423.5SL       C0201H13                    C311
78.22423.5SL       C0201H13                    C312
78.22423.5SL       C0201H13                    C313
78.22423.5SL       C0201H13                    C314
78.22423.5SL       C0201H13                    C315
78.22423.5SL       C0201H13                    C316
78.22423.5SL       C0201H13                    C317
78.22423.5SL       C0201H13                    C318
78.22423.5SL       C0201H13                    C319
78.22423.5SL       C0201H13                    C320
78.22423.5SL       C0201H13                    C321
78.22423.5SL       C0201H13                    C322
78.22423.5SL       C0201H13                    C323
78.22423.5SL       C0201H13                    C324
78.22423.5SL       C0201H13                    C325
78.22423.5SL       C0201H13                    C326
078.10321.02S1     C0201H13                    C327
078.10321.02S1     C0201H13                    C328
078.10321.02S1     C0201H13                    C329
078.10321.02S1     C0201H13                    C330
078.10321.02S1     C0201H13                    C331
078.10321.02S1     C0201H13                    C332
078.10321.02S1     C0201H13                    C333
78.15034.1FL       C402H22                     C334
78.15034.1FL       C402H22                     C335
078.10321.02S1     C0201H13                    C336
078.10321.02S1     C0201H13                    C337
078.10321.02S1     C0201H13                    C338
078.10321.02S1     C0201H13                    C339
078.10321.02S1     C0201H13                    C340
078.10321.02S1     C0201H13                    C341
078.10321.02S1     C0201H13                    C342
078.10321.02S1     C0201H13                    C343
078.10321.02S1     C0201H13                    C344
78.10421.2FL       C402H22                     C345
78.10322.2FL       C402H22                     C346
078.47522.0211     C805H58                     C347
78.10521.2BL       C603H36                     C348
78.10421.2FL       C402H22                     C349
78.10421.2FL       C402H22                     C350
078.22610.08B1     C603H40                     C351
78.10620.21L       C805H58                     C352
078.10521.08F1     C402-TO0D2H24               C353
78.10421.2FL       C402H22                     C354
078.22610.08B1     C603H40                     C355
78.10620.21L       C805H58                     C356
078.10521.08F1     C402-TO0D2H24               C357
78.10421.2FL       C402H22                     C358
078.22610.08B1     C603H40                     C359
78.10620.21L       C805H58                     C360
078.10521.08F1     C402-TO0D2H24               C361
78.10421.2FL       C402H22                     C362
078.22610.08B1     C603H40                     C363
78.10620.21L       C805H58                     C364
078.10521.08F1     C402-TO0D2H24               C365
78.10421.2FL       C402H22                     C366
078.22610.08B1     C603H40                     C367
78.10620.21L       C805H58                     C368
078.10521.08F1     C402-TO0D2H24               C369
78.10421.2FL       C402H22                     C370
078.22610.08B1     C603H40                     C371
78.10620.21L       C805H58                     C372
078.10521.08F1     C402-TO0D2H24               C373
78.10421.2FL       C402H22                     C374
78.10421.2FL       C402H22                     C375
78.10421.2FL       C402H22                     C376
078.22610.08B1     C603H40                     C377
78.10620.21L       C805H58                     C378
078.10521.08F1     C402-TO0D2H24               C379
78.10421.2FL       C402H22                     C380
78.10421.2FL       C402H22                     C381
78.10421.2FL       C402H22                     C382
78.10710.52L       C1206H71                    C383
078.22610.08B1     C603H40                     C384
078.10521.08F1     C402-TO0D2H24               C385
78.10420.50L       C0201H13                    C386
78.10420.50L       C0201H13                    C387
78.10420.50L       C0201H13                    C388
78.10420.50L       C0201H13                    C389
78.10420.50L       C0201H13                    C390
78.10420.50L       C0201H13                    C391
78.10420.50L       C0201H13                    C392
78.10420.50L       C0201H13                    C393
78.10710.52L       C1206H71                    C394
78.10710.52L       C1206H71                    C395
078.10521.08F1     C402-TO0D2H24               C396
78.10421.2FL       C402H22                     C397
78.10421.2FL       C402H22                     C398
78.10421.2FL       C402H22                     C399
78.10421.2FL       C402H22                     C400
78.10421.2FL       C402H22                     C401
78.10421.2FL       C402H22                     C402
78.10421.2FL       C402H22                     C403
78.10421.2FL       C402H22                     C404
78.10620.21L       C805H58                     C405
78.10620.21L       C805H58                     C406
78.10620.21L       C805H58                     C407
78.10620.21L       C805H58                     C408
78.10620.21L       C805H58                     C409
78.10620.21L       C805H58                     C410
78.10510.5SL       C0201H14                    C411
78.10510.5SL       C0201H14                    C412
78.10510.5SL       C0201H14                    C413
78.10510.5SL       C0201H14                    C414
78.10510.5SL       C0201H14                    C415
78.10510.5SL       C0201H14                    C416
78.10420.50L       C0201H13                    C417
78.10420.50L       C0201H13                    C418
78.10420.50L       C0201H13                    C419
78.10420.50L       C0201H13                    C420
78.10420.50L       C0201H13                    C421
78.10420.50L       C0201H13                    C422
78.10420.50L       C0201H13                    C423
78.10420.50L       C0201H13                    C424
78.10420.50L       C0201H13                    C425
78.10420.50L       C0201H13                    C426
78.10420.50L       C0201H13                    C427
78.10420.50L       C0201H13                    C428
78.10420.50L       C0201H13                    C429
78.10420.50L       C0201H13                    C430
78.10420.50L       C0201H13                    C431
78.10420.50L       C0201H13                    C432
78.10420.50L       C0201H13                    C433
78.10420.50L       C0201H13                    C434
78.10420.50L       C0201H13                    C435
78.10420.50L       C0201H13                    C436
78.10420.50L       C0201H13                    C437
78.10420.50L       C0201H13                    C438
78.10420.50L       C0201H13                    C439
78.10420.50L       C0201H13                    C440
78.10420.50L       C0201H13                    C441
78.10420.50L       C0201H13                    C442
78.10420.50L       C0201H13                    C443
78.10224.2FL       C402H22                     C444
78.10224.2FL       C402H22                     C445
78.10224.2FL       C402H22                     C446
78.10224.2FL       C402H22                     C447
78.10224.2FL       C402H22                     C448
78.10224.2FL       C402H22                     C449
78.10224.2FL       C402H22                     C450
78.10224.2FL       C402H22                     C451
78.10420.50L       C0201H13                    C452
78.10420.50L       C0201H13                    C453
78.10420.50L       C0201H13                    C454
78.10420.50L       C0201H13                    C455
78.10420.50L       C0201H13                    C456
78.10420.50L       C0201H13                    C457
78.10420.50L       C0201H13                    C458
78.10420.50L       C0201H13                    C459
78.10420.50L       C0201H13                    C460
78.10420.50L       C0201H13                    C461
78.10420.50L       C0201H13                    C462
78.10420.50L       C0201H13                    C463
78.10420.50L       C0201H13                    C464
78.10420.50L       C0201H13                    C465
78.10420.50L       C0201H13                    C466
78.10420.50L       C0201H13                    C467
78.10420.50L       C0201H13                    C468
78.10420.50L       C0201H13                    C469
78.10420.50L       C0201H13                    C470
78.10420.50L       C0201H13                    C471
78.10420.50L       C0201H13                    C472
78.10420.50L       C0201H13                    C473
78.10420.50L       C0201H13                    C474
78.10420.50L       C0201H13                    C475
78.10420.50L       C0201H13                    C476
78.10420.50L       C0201H13                    C477
78.10420.50L       C0201H13                    C478
78.10420.50L       C0201H13                    C479
78.10420.50L       C0201H13                    C480
78.10420.50L       C0201H13                    C481
078.10521.08F1     C402-TO0D2H24               C482
078.10521.08F1     C402-TO0D2H24               C483
078.10521.08F1     C402-TO0D2H24               C484
078.10521.08F1     C402-TO0D2H24               C485
078.10521.08F1     C402-TO0D2H24               C486
078.10521.08F1     C402-TO0D2H24               C487
78.10420.50L       C0201H13                    C488
78.10420.50L       C0201H13                    C489
78.10420.50L       C0201H13                    C490
78.10420.50L       C0201H13                    C491
78.10420.50L       C0201H13                    C492
78.10420.50L       C0201H13                    C493
78.10224.2FL       C402H22                     C494
78.10224.2FL       C402H22                     C495
78.10224.2FL       C402H22                     C496
78.10224.2FL       C402H22                     C497
78.10224.2FL       C402H22                     C498
78.10224.2FL       C402H22                     C499
78.10224.2FL       C402H22                     C500
78.10224.2FL       C402H22                     C501
78.10421.2FL       C402H22                     C502
78.10421.2FL       C402H22                     C503
78.10421.2FL       C402H22                     C504
78.10421.2FL       C402H22                     C505
78.10421.2FL       C402H22                     C506
78.10421.2FL       C402H22                     C507
78.10421.2FL       C402H22                     C508
78.10421.2FL       C402H22                     C509
78.10421.2FL       C402H22                     C510
078.47522.0211     C805H58                     C511
78.10420.50L       C0201H13                    C512
78.10420.50L       C0201H13                    C513
78.10420.50L       C0201H13                    C514
78.10421.2FL       C402H22                     C515
78.10421.2FL       C402H22                     C516
78.10421.2FL       C402H22                     C517
078.10521.08F1     C402-TO0D2H24               C518
78.10421.2FL       C402H22                     C519
078.10521.08F1     C402-TO0D2H24               C520
78.10421.2FL       C402H22                     C521
78.15322.2FL       C402H22                     C522
78.10421.2FL       C402H22                     C523
78.10421.2FL       C402H22                     C524
78.10421.2FL       C402H22                     C525
78.10421.2FL       C402H22                     C526
078.10621.0211     C805H58                     C527
78.10421.2FL       C402H22                     C528
78.10322.2FL       C402H22                     C529
78.10421.2FL       C402H22                     C530
78.10420.50L       C0201H13                    C531
78.10421.2FL       C402H22                     C532
78.10421.2FL       C402H22                     C533
78.10421.2FL       C402H22                     C534
78.10421.2FL       C402H22                     C535
78.10420.50L       C0201H13                    C536
78.10420.50L       C0201H13                    C537
78.10420.50L       C0201H13                    C538
78.10420.50L       C0201H13                    C539
78.10420.50L       C0201H13                    C540
78.10421.2FL       C402H22                     C541
78.10421.2FL       C402H22                     C542
78.10421.2FL       C402H22                     C545
78.10421.2FL       C402H22                     C548
78.10421.2FL       C402H22                     C549
78.10421.2FL       C402H22                     C550
78.10421.2FL       C402H22                     C551
78.10421.2FL       C402H22                     C552
78.10421.2FL       C402H22                     C557
78.10421.2FL       C402H22                     C558
78.10421.2FL       C402H22                     C559
78.10421.2FL       C402H22                     C560
78.10421.2FL       C402H22                     C561
78.10421.2FL       C402H22                     C562
078.10621.0211     C805H58                     C563
078.10621.0211     C805H58                     C564
078.10621.0211     C805H58                     C565
078.10621.0211     C805H58                     C566
78.10421.2FL       C402H22                     C570
78.10421.2FL       C402H22                     C571
78.15322.2FL       C402H22                     C574
78.10421.2FL       C402H22                     C575
78.10421.2FL       C402H22                     C576
78.10421.2FL       C402H22                     C577
78.10420.50L       C0201H13                    C578
78.10420.50L       C0201H13                    C579
78.10420.50L       C0201H13                    C580
78.10420.50L       C0201H13                    C581
78.10420.50L       C0201H13                    C582
78.10420.50L       C0201H13                    C583
78.10420.50L       C0201H13                    C584
78.10420.50L       C0201H13                    C585
78.10420.50L       C0201H13                    C586
78.10420.50L       C0201H13                    C587
78.10420.50L       C0201H13                    C588
78.10420.50L       C0201H13                    C589
78.10420.50L       C0201H13                    C590
78.10420.50L       C0201H13                    C591
78.10420.50L       C0201H13                    C592
78.10421.2FL       C402H22                     C594
078.10621.0211     C805H58                     C595
78.10421.2FL       C402H22                     C596
78.10620.21L       C805H58                     C597
78.10421.2FL       C402H22                     C598
78.10421.2FL       C402H22                     C599
78.10421.2FL       C402H22                     C600
78.10421.2FL       C402H22                     C601
78.47124.2FL       C402H22                     C602
78.10521.2BL       C603H36                     C603
78.10421.2FL       C402H22                     C604
78.10224.2FL       C402H22                     C605
78.10521.2BL       C603H36                     C606
078.47522.0211     C805H58                     C607
78.47422.2BL       C603H36                     C608
78.10620.21L       C805H58                     C609
078.10321.02S1     C0201H13                    C610
78.10224.2FL       C402H22                     C611
78.10322.2FL       C402H22                     C612
78.10322.2FL       C402H22                     C613
78.10620.21L       C805H58                     C614
78.10224.2FL       C402H22                     C615
078.47522.0211     C805H58                     C616
78.10620.21L       C805H58                     C617
78.10224.2FL       C402H22                     C618
78.10522.2BL       C603H36                     C619
78.10522.2BL       C603H36                     C620
78.10521.2BL       C603H36                     C621
78.10522.2BL       C603H36                     C622
78.10522.2BL       C603H36                     C623
78.22124.2FL       C402H22                     C624
78.10224.2FL       C402H22                     C625
78.33421.2BL       C603H36                     C626
78.10620.21L       C805H58                     C627
78.10620.21L       C805H58                     C628
78.10620.21L       C805H58                     C629
78.10620.21L       C805H58                     C630
078.10621.0211     C805H58                     C635
078.10621.0211     C805H58                     C636
078.10621.0211     C805H58                     C637
78.10521.2BL       C603H36                     C638
078.47522.0211     C805H58                     C639
78.10224.2FL       C402H22                     C640
78.10421.2FL       C402H22                     C641
078.68034.C1F1     C402H22                     C642
078.10621.0211     C805H58                     C643
078.10621.0211     C805H58                     C644
078.10621.0211     C805H58                     C645
78.10522.2BL       C603H36                     C646
78.10421.2FL       C402H22                     C647
78.10322.2FL       C402H22                     C648
78.10521.2BL       C603H36                     C649
78.10521.2BL       C603H36                     C650
78.10424.2BL       C603H36                     C651
78.10424.2BL       C603H36                     C652
78.10424.2BL       C603H36                     C653
78.10224.2FL       C402H22                     C655
78.10424.2BL       C603H36                     C656
078.10621.0211     C805H58                     C657
78.47222.2FL       C402H24                     C658
78.68224.2FL       C402H22                     C659
78.10424.2BL       C603H36                     C660
78.68224.2FL       C402H22                     C661
78.10322.2FL       C402H22                     C662
78.10424.2BL       C603H36                     C663
78.10424.2BL       C603H36                     C664
78.22620.22L       C1206H71                    C665
078.10621.0211     C805H58                     C666
078.10621.0211     C805H58                     C667
078.10621.0211     C805H58                     C668
078.10621.0211     C805H58                     C669
078.10621.0211     C805H58                     C670
078.10621.0211     C805H58                     C671
78.10424.2BL       C603H36                     C672
78.10424.2BL       C603H36                     C673
78.10421.2FL       C402H22                     C674
78.10424.2BL       C603H36                     C675
078.68034.C1F1     C402H22                     C676
078.10321.02S1     C0201H13                    C677
078.10321.02S1     C0201H13                    C678
078.10321.02S1     C0201H13                    C679
078.10321.02S1     C0201H13                    C680
078.10321.02S1     C0201H13                    C681
078.10321.02S1     C0201H13                    C682
078.10321.02S1     C0201H13                    C683
78.10620.21L       C805H58                     C684
78.10620.21L       C805H58                     C685
78.10620.21L       C805H58                     C686
78.10620.21L       C805H58                     C687
78.10620.21L       C805H58                     C688
78.10421.2FL       C402H22                     C689
78.10620.21L       C805H58                     C690
78.47422.2BL       C603H36                     C691
78.10421.2FL       C402H22                     C692
78.10421.2FL       C402H22                     C693
78.10620.21L       C805H58                     C694
78.10620.21L       C805H58                     C695
78.10424.2BL       C603H36                     C696
78.10424.2BL       C603H36                     C697
078.10621.0211     C805H58                     C698
078.10621.0211     C805H58                     C699
078.10621.0211     C805H58                     C700
078.10621.0211     C805H58                     C701
078.10621.0211     C805H58                     C702
78.10620.21L       C805H58                     C703
78.10620.21L       C805H58                     C704
78.10421.2FL       C402H22                     C705
78.10620.21L       C805H58                     C706
78.10620.21L       C805H58                     C707
78.10620.21L       C805H58                     C708
078.10621.0211     C805H58                     C709
78.22224.2FL       C402H22                     C710
78.22224.2FL       C402H22                     C711
078.10521.08F1     C402-TO0D2H24               C712
78.10424.2BL       C603H36                     C713
78.10521.2BL       C603H36                     C714
78.10421.2FL       C402H22                     C715
078.22610.08B1     C603H40                     C719
78.10710.52L       C1206H71                    C720
78.10421.2FL       C402H22                     C721
78.10421.2FL       C402H22                     C730
78.10421.2FL       C402H22                     C731
78.10421.2FL       C402H22                     C732
78.10421.2FL       C402H22                     C733
78.10421.2FL       C402H22                     C734
78.10421.2FL       C402H22                     C735
78.10421.2FL       C402H22                     C736
78.22322.2FL       C402H22                     C737
78.10421.2FL       C402H22                     C738
78.22521.21L       C805H58                     C739
78.10421.2FL       C402H22                     C740
78.10421.2FL       C402H22                     C741
78.10421.2FL       C402H22                     C742
78.10421.2FL       C402H22                     C743
78.22224.2FL       C402H22                     C744
020.80777.0001     PREFIT-12P-162281H396       CN1
020.80963.0001     PREFIT-342P-648260H400      CN2
020.80815.0011     PREFIT-76P-144260H400       CN6
83.R5003.H8H       SOD323AKH38                 D2
83.R5003.H8H       SOD323AKH38                 D3
83.SMF15.0AH       SOD123AK-2H43               D37
21.D0358.207       A2005WR0-2CX7PBS            DB1
021.D0225.0104     G800MR304010HR              DEBUG1
021.D0225.0104     G800MR304010HR              DEBUG2
ZZ.CON2C.XXX       CON2C-U                     G3
ZZ.CON2C.XXX       CON2C-U                     G5
68.00224.201       L805H42                     L1
68.00224.201       L805H42                     L2
68.00224.201       L805H42                     L3
68.00224.201       L805H42                     L4
68.00224.201       L805H42                     L5
68.00084.831       L20125H42                   L6
68.00224.051       L805H42                     L7
68.00224.051       L805H42                     L8
68.00224.051       L805H42                     L9
68.00224.051       L805H42                     L10
68.00224.051       L805H42                     L11
68.00224.051       L805H42                     L12
68.00224.051       L805H42                     L13
68.00224.051       L805H42                     L14
68.00224.051       L805H42                     L15
68.00224.051       L805H42                     L16
68.00224.051       L805H42                     L17
68.00224.051       L805H42                     L18
68.00224.201       L805H42                     L19
68.00224.201       L805H42                     L20
68.00224.201       L805H42                     L21
68.00224.201       L805H42                     L22
68.00224.201       L805H42                     L23
68.00224.201       L805H42                     L24
68.00224.201       L805H42                     L25
68.00224.051       L805H42                     L26
68.00395.001       L9546-152127H121            L27
68.00084.831       L20125H42                   L28
68.2R21A.20B       L7066-1830-UH119            L29
68.00084.771       L451616H71                  L30
068.1812N.1021     L105080-2221H276            L31
68.00084.771       L451616H71                  L32
68.R2410.20A       L7267-1630H158              L33
68.3R310.20V       L7066-1830-UH119            L34
68.00224.051       L805H42                     L35
83.01921.S70       LED1608AKH40                LED1
83.01921.S70       LED1608AKH40                LED2
ZZ.00PAD.QM1       HOLE709R146-3P-S3           LHOLE1
20.82057.036       PREFIT-36P-152240-UH561     MSAS1
ZZ.00PAD.M21       0R0603-PAD-1-U              P1
ZZ.CON2C.XXX       CON2C-U                     PSP1
ZZ.CON2C.XXX       CON2C-U                     PSP2
084.3K324.0031     SOT23DGS2D4H35              Q2
084.3K324.0031     SOT23DGS2D4H35              Q3
084.3K324.0031     SOT23DGS2D4H35              Q4
84.2N702.031       SOT23DGS2D4H44              Q5
84.2N702.031       SOT23DGS2D4H44              Q6
75.87355.071       PPAK-8P-G510321H62          Q7
84.2N702.031       SOT23DGS2D4H44              Q8
084.3K324.0031     SOT23DGS2D4H35              Q9
84.2N702.031       SOT23DGS2D4H44              Q10
084.3K324.0031     SOT23DGS2D4H35              Q11
84.2N702.031       SOT23DGS2D4H44              Q12
84.2N702.I31       SOT23DGS2D4H44              Q13
84.2N702.031       SOT23DGS2D4H44              Q14
084.3K324.0031     SOT23DGS2D4H35              Q16
84.2N702.031       SOT23DGS2D4H44              Q20
84.2N702.031       SOT23DGS2D4H44              Q22
84.0R925.03N       LFPAK-5PH48-U               Q23
84.2N702.I31       SOT23DGS2D4H44              Q34
84.08878.A37       SOIC8H69                    Q35
84.08878.A37       SOIC8H69                    Q36
84.03904.T11       SOT23CBE2D4H44              Q37
64.10025.6DL       R402H16                     R1
64.10025.6DL       R402H16                     R2
64.10025.6DL       R402H16                     R3
64.45315.6DL       R402H16                     R4
64.45315.6DL       R402H16                     R8
64.10015.6DL       R402H16                     R9
64.10015.6DL       R402H16                     R10
64.10R05.6DL       R402H14                     R11
63.R0034.1DL       R402H16                     R12
63.R0034.1DL       R402H16                     R13
64.R0035.L1L       RL3115-4PH25                R14
064.41215.06DS     R402H16                     R15
064.51015.06DS     R402H16                     R16
63.10434.L1L       R402H15                     R17
63.10434.L1L       R402H15                     R18
63.10434.L1L       R402H15                     R19
64.6342D.6DL       R402H16                     R20
64.22635.6DL       R402H16                     R22
63.R0031.16L       R805H24                     R24
63.R0034.1DL       R402H16                     R25
63.R0031.16L       R805H24                     R26
64.10025.6DL       R402H16                     R27
63.2R233.15L       R603H22                     R28
64.10R05.55L       R603H22                     R29
64.47535.6DL       R402H16                     R31
64.47015.6DL       R402H16                     R33
64.47515.6DL       R402H16                     R34
64.47515.6DL       R402H16                     R35
64.47015.6DL       R402H16                     R36
64.47015.6DL       R402H16                     R37
64.47015.6DL       R402H16                     R38
64.47015.6DL       R402H16                     R39
64.47015.6DL       R402H16                     R40
64.47015.6DL       R402H16                     R41
64.47015.6DL       R402H16                     R42
64.47015.6DL       R402H16                     R43
64.47015.6DL       R402H16                     R44
64.47015.6DL       R402H16                     R45
64.47015.6DL       R402H16                     R46
64.47515.6DL       R402H16                     R47
64.47015.6DL       R402H16                     R48
64.47015.6DL       R402H16                     R49
64.47015.6DL       R402H16                     R50
64.47015.6DL       R402H16                     R51
64.47015.6DL       R402H16                     R52
64.47015.6DL       R402H16                     R53
64.47015.6DL       R402H16                     R54
64.47015.6DL       R402H16                     R55
64.47015.6DL       R402H16                     R56
64.47015.6DL       R402H16                     R57
64.47015.6DL       R402H16                     R58
64.47015.6DL       R402H16                     R59
64.47015.6DL       R402H16                     R60
64.47015.6DL       R402H16                     R61
64.10015.6DL       R402H16                     R62
64.10015.6DL       R402H16                     R63
64.47015.6DL       R402H16                     R64
64.47015.6DL       R402H16                     R65
64.10015.6DL       R402H16                     R66
64.10015.6DL       R402H16                     R67
64.10015.6DL       R402H16                     R68
64.10015.6DL       R402H16                     R69
64.10015.6DL       R402H16                     R70
64.10015.6DL       R402H16                     R71
64.47015.6DL       R402H16                     R72
64.47015.6DL       R402H16                     R73
64.47015.6DL       R402H16                     R74
63.R0034.1DL       R402H16                     R75
63.R0034.1DL       R402H16                     R76
64.47015.6DL       R402H16                     R77
64.47015.6DL       R402H16                     R78
64.47015.6DL       R402H16                     R79
63.R0034.1DL       R402H16                     R80
64.10025.6DL       R402H16                     R81
64.47015.6DL       R402H16                     R83
63.R0031.16L       R805H24                     R84
64.47515.6DL       R402H16                     R85
64.47515.6DL       R402H16                     R86
64.47515.6DL       R402H16                     R87
63.R0034.1DL       R402H16                     R88
63.R0034.1DL       R402H16                     R89
63.R0034.1DL       R402H16                     R90
64.20035.6DL       R402H16                     R91
63.R0034.1DL       R402H16                     R92
64.47515.6DL       R402H16                     R93
64.15005.6DL       R402H16                     R94
63.R0034.1DL       R402H16                     R95
64.10035.6DL       R402H16                     R96
64.10025.6DL       R402H16                     R97
64.28715.6DL       R402H16                     R98
64.35715.6DL       R402H16                     R99
63.R0034.1DL       R402H16                     R100
63.R0034.1DL       R402H16                     R101
63.R0034.1DL       R402H16                     R102
63.R0034.1DL       R402H16                     R103
64.47515.6DL       R402H16                     R104
63.R0034.1DL       R402H16                     R105
64.47515.6DL       R402H16                     R106
64.47515.6DL       R402H16                     R107
64.47515.6DL       R402H16                     R108
64.47515.6DL       R402H16                     R109
64.47515.6DL       R402H16                     R110
64.47515.6DL       R402H16                     R111
64.47515.6DL       R402H16                     R112
64.47515.6DL       R402H16                     R113
64.47515.6DL       R402H16                     R114
64.30115.6DL       R402H16                     R115
64.47515.6DL       R402H16                     R116
64.47515.6DL       R402H16                     R117
64.47515.6DL       R402H16                     R118
64.47515.6DL       R402H16                     R119
64.10025.6DL       R402H16                     R120
63.R0034.1DL       R402H16                     R121
64.47515.6DL       R402H16                     R122
64.47515.6DL       R402H16                     R123
64.47515.6DL       R402H16                     R124
64.47515.6DL       R402H16                     R125
64.47015.6DL       R402H16                     R126
64.47015.6DL       R402H16                     R127
64.47015.6DL       R402H16                     R128
64.10025.6DL       R402H16                     R129
64.47015.6DL       R402H16                     R130
64.47015.6DL       R402H16                     R131
63.R0034.1DL       R402H16                     R132
63.R0034.1DL       R402H16                     R133
64.R5105.55L       R603H22                     R134
64.47015.6DL       R402H16                     R135
64.47515.6DL       R402H16                     R136
64.47515.6DL       R402H16                     R137
64.47515.6DL       R402H16                     R138
64.10025.6DL       R402H16                     R139
64.34025.6DL       R402H16                     R140
64.47015.6DL       R402H16                     R141
64.47015.6DL       R402H16                     R142
64.47015.6DL       R402H16                     R143
64.47015.6DL       R402H16                     R144
64.47015.6DL       R402H16                     R145
64.47015.6DL       R402H16                     R146
64.47015.6DL       R402H16                     R147
64.47515.6DL       R402H16                     R148
64.10025.6DL       R402H16                     R149
64.47515.6DL       R402H16                     R150
64.10R05.6DL       R402H14                     R151
64.10R05.6DL       R402H14                     R152
64.10R05.6DL       R402H14                     R153
64.10R05.6DL       R402H14                     R154
64.10R05.6DL       R402H14                     R155
63.R0034.1DL       R402H16                     R156
64.R5105.55L       R603H22                     R157
64.R5105.55L       R603H22                     R158
64.R5105.55L       R603H22                     R159
64.R5105.55L       R603H22                     R160
64.R5105.55L       R603H22                     R161
64.R5105.55L       R603H22                     R162
64.R5105.55L       R603H22                     R163
64.R5105.55L       R603H22                     R164
64.R5105.55L       R603H22                     R165
64.R5105.55L       R603H22                     R166
64.R5105.55L       R603H22                     R167
64.R5105.55L       R603H22                     R168
63.R0034.1DL       R402H16                     R169
64.51R05.6DL       R402H16                     R170
64.10025.6DL       R402H16                     R171
64.10025.6DL       R402H16                     R172
64.51R05.6DL       R402H16                     R173
63.R0034.1DL       R402H16                     R174
64.10025.6DL       R402H16                     R175
64.10025.6DL       R402H16                     R176
63.R0034.1DL       R402H16                     R177
64.10025.6DL       R402H16                     R178
64.22015.6DL       R402H16                     R179
64.22015.6DL       R402H16                     R180
64.22015.6DL       R402H16                     R181
64.22015.6DL       R402H16                     R182
64.22015.6DL       R402H16                     R183
64.22015.6DL       R402H16                     R184
64.22015.6DL       R402H16                     R185
64.47015.6DL       R402H16                     R186
64.22015.6DL       R402H16                     R187
64.22015.6DL       R402H16                     R188
64.22015.6DL       R402H16                     R189
64.22015.6DL       R402H16                     R190
64.22015.6DL       R402H16                     R191
64.22015.6DL       R402H16                     R192
63.R0034.1DL       R402H16                     R193
64.22015.6DL       R402H16                     R194
64.22015.6DL       R402H16                     R195
64.22015.6DL       R402H16                     R196
64.22015.6DL       R402H16                     R197
64.47015.6DL       R402H16                     R198
64.47015.6DL       R402H16                     R199
64.22015.6DL       R402H16                     R200
64.47015.6DL       R402H16                     R201
63.R0034.1DL       R402H16                     R202
64.22015.6DL       R402H16                     R203
64.22015.6DL       R402H16                     R204
63.R0034.1DL       R402H16                     R205
63.R0034.1DL       R402H16                     R206
63.R0034.1DL       R402H16                     R207
64.47015.6DL       R402H16                     R208
64.47015.6DL       R402H16                     R209
63.R0034.1DL       R402H16                     R210
63.R0034.1DL       R402H16                     R211
64.47515.6DL       R402H16                     R212
64.10025.6DL       R402H16                     R213
64.10025.6DL       R402H16                     R214
64.10025.6DL       R402H16                     R215
64.10025.6DL       R402H16                     R216
64.10025.6DL       R402H16                     R217
64.10025.6DL       R402H16                     R218
64.10025.6DL       R402H16                     R219
64.10025.6DL       R402H16                     R220
64.10025.6DL       R402H16                     R221
64.10025.6DL       R402H16                     R222
64.10025.6DL       R402H16                     R223
64.10025.6DL       R402H16                     R224
64.10025.6DL       R402H16                     R225
64.10025.6DL       R402H16                     R226
64.10025.6DL       R402H16                     R227
64.10025.6DL       R402H16                     R228
64.10025.6DL       R402H16                     R229
64.10025.6DL       R402H16                     R230
64.10025.6DL       R402H16                     R231
64.10025.6DL       R402H16                     R232
64.47015.6DL       R402H16                     R233
64.47015.6DL       R402H16                     R234
64.47015.6DL       R402H16                     R235
64.47515.6DL       R402H16                     R236
64.10025.6DL       R402H16                     R237
64.15005.6DL       R402H16                     R238
64.15005.6DL       R402H16                     R239
63.30234.1DL       R402H16                     R240
64.10025.6DL       R402H16                     R241
64.47015.6DL       R402H16                     R242
63.R0034.1DL       R402H16                     R243
64.47015.6DL       R402H16                     R244
63.R0034.1DL       R402H16                     R245
64.10025.6DL       R402H16                     R246
64.47015.6DL       R402H16                     R247
64.47015.6DL       R402H16                     R248
64.10025.6DL       R402H16                     R249
64.10025.6DL       R402H16                     R250
64.10025.6DL       R402H16                     R251
64.10025.6DL       R402H16                     R252
64.10025.6DL       R402H16                     R253
64.10025.6DL       R402H16                     R254
64.10025.6DL       R402H16                     R255
64.10025.6DL       R402H16                     R256
64.10025.6DL       R402H16                     R257
64.47015.6DL       R402H16                     R258
64.47015.6DL       R402H16                     R259
64.47015.6DL       R402H16                     R260
64.47015.6DL       R402H16                     R261
64.47015.6DL       R402H16                     R262
64.47015.6DL       R402H16                     R263
64.47015.6DL       R402H16                     R264
64.47015.6DL       R402H16                     R265
64.47015.6DL       R402H16                     R266
64.47015.6DL       R402H16                     R267
64.47015.6DL       R402H16                     R268
64.10025.6DL       R402H16                     R269
64.10025.6DL       R402H16                     R270
64.10025.6DL       R402H16                     R271
64.10025.6DL       R402H16                     R272
64.10025.6DL       R402H16                     R273
64.10025.6DL       R402H16                     R274
64.47015.6DL       R402H16                     R275
64.47015.6DL       R402H16                     R276
64.10R05.6DL       R402H14                     R277
64.10R05.6DL       R402H14                     R278
64.10R05.6DL       R402H14                     R279
64.10R05.6DL       R402H14                     R280
64.10R05.6DL       R402H14                     R281
64.10R05.6DL       R402H14                     R282
64.10R05.6DL       R402H14                     R283
64.R5105.55L       R603H22                     R284
64.R5105.55L       R603H22                     R285
64.10025.6DL       R402H16                     R286
64.10025.6DL       R402H16                     R287
63.R0034.1DL       R402H16                     R288
63.R0034.1DL       R402H16                     R289
63.R0034.1DL       R402H16                     R290
64.10025.6DL       R402H16                     R291
63.R0034.1DL       R402H16                     R292
63.R0034.1DL       R402H16                     R293
63.R0034.1DL       R402H16                     R294
63.R0034.1DL       R402H16                     R295
63.R0034.1DL       R402H16                     R296
63.R0034.1DL       R402H16                     R297
63.R0034.1DL       R402H16                     R298
63.R0034.1DL       R402H16                     R299
64.10025.6DL       R402H16                     R300
64.47515.6DL       R402H16                     R301
64.47515.6DL       R402H16                     R302
64.10025.6DL       R402H16                     R303
64.10025.6DL       R402H16                     R304
64.10025.6DL       R402H16                     R305
64.10025.6DL       R402H16                     R306
64.10025.6DL       R402H16                     R307
64.10025.6DL       R402H16                     R308
64.10025.6DL       R402H16                     R309
64.10025.6DL       R402H16                     R310
64.61935.6DL       R402H16                     R311
64.10025.6DL       R402H16                     R312
64.38315.6DL       R402H16                     R313
63.R0034.1DL       R402H16                     R314
63.R0034.1DL       R402H16                     R315
64.86635.6DL       R402H16                     R316
64.47015.6DL       R402H16                     R317
64.69825.6DL       R402H16                     R320
64.10015.6DL       R402H16                     R321
64.10015.6DL       R402H16                     R322
64.10015.6DL       R402H16                     R323
64.10035.6DL       R402H16                     R324
63.R0034.1DL       R402H16                     R325
63.R0034.1DL       R402H16                     R326
63.R0034.1DL       R402H16                     R327
63.R0034.1DL       R402H16                     R328
64.47015.6DL       R402H16                     R329
64.47015.6DL       R402H16                     R330
64.47015.6DL       R402H16                     R331
64.47015.6DL       R402H16                     R332
64.47015.6DL       R402H16                     R333
64.47015.6DL       R402H16                     R334
64.47015.6DL       R402H16                     R335
64.47015.6DL       R402H16                     R336
64.47015.6DL       R402H16                     R337
63.R0034.1DL       R402H16                     R341
64.47015.6DL       R402H16                     R344
64.47015.6DL       R402H16                     R345
64.47015.6DL       R402H16                     R346
63.R0034.1DL       R402H16                     R347
63.R0034.1DL       R402H16                     R348
64.47515.6DL       R402H16                     R350
63.R0034.1DL       R402H16                     R351
64.10015.6DL       R402H16                     R352
64.10015.6DL       R402H16                     R353
63.R0034.1DL       R402H16                     R354
63.R0034.1DL       R402H16                     R355
63.82234.1DL       R402H16                     R356
64.47015.6DL       R402H16                     R357
64.47015.6DL       R402H16                     R358
64.10015.6DL       R402H16                     R359
64.47015.6DL       R402H16                     R360
64.47015.6DL       R402H16                     R361
64.47015.6DL       R402H16                     R362
64.47015.6DL       R402H16                     R363
64.47015.6DL       R402H16                     R364
64.47015.6DL       R402H16                     R365
63.R0034.1DL       R402H16                     R366
63.R0034.1DL       R402H16                     R367
64.47015.6DL       R402H16                     R368
64.47015.6DL       R402H16                     R369
64.47015.6DL       R402H16                     R370
64.47015.6DL       R402H16                     R371
63.R0034.1DL       R402H16                     R372
64.10025.6DL       R402H16                     R373
64.47015.6DL       R402H16                     R374
64.10025.6DL       R402H16                     R375
64.47015.6DL       R402H16                     R376
64.15025.6DL       R402H16                     R377
64.15015.6DL       R402H16                     R378
64.3R015.16L       R805H24                     R379
64.10015.6DL       R402H16                     R380
64.2R205.55L       R603H22                     R381
63.R0031.16L       R805H24                     R382
63.R0034.1DL       R402H16                     R383
63.R0034.1DL       R402H16                     R386
63.R0034.1DL       R402H16                     R387
64.47015.6DL       R402H16                     R393
64.10025.6DL       R402H16                     R394
64.10025.6DL       R402H16                     R395
64.10025.6DL       R402H16                     R396
64.47015.6DL       R402H16                     R397
64.10025.6DL       R402H16                     R398
64.80615.6DL       R402H16                     R399
64.10015.6DL       R402H16                     R400
63.62334.1DL       R402H16                     R401
63.R0034.1DL       R402H16                     R402
64.10025.6DL       R402H16                     R403
64.10025.6DL       R402H16                     R404
64.47015.6DL       R402H16                     R405
63.R0034.1DL       R402H16                     R406
64.20035.6DL       R402H16                     R407
64.10015.6DL       R402H16                     R408
64.10015.6DL       R402H16                     R409
63.R0034.1DL       R402H16                     R410
64.20035.6DL       R402H16                     R411
64.20035.6DL       R402H16                     R412
64.10015.6DL       R402H16                     R413
64.10015.6DL       R402H16                     R414
63.R0034.1DL       R402H16                     R415
64.20035.6DL       R402H16                     R416
64.20035.6DL       R402H16                     R417
64.10015.6DL       R402H16                     R418
64.10015.6DL       R402H16                     R419
64.20035.6DL       R402H16                     R420
64.10015.6DL       R402H16                     R421
64.10015.6DL       R402H16                     R422
63.R0034.1DL       R402H16                     R423
63.R0034.1DL       R402H16                     R424
64.20035.6DL       R402H16                     R425
64.20035.6DL       R402H16                     R426
64.20035.6DL       R402H16                     R427
64.10015.6DL       R402H16                     R428
64.10015.6DL       R402H16                     R429
64.20035.6DL       R402H16                     R430
64.10015.6DL       R402H16                     R431
64.10015.6DL       R402H16                     R432
63.R0034.1DL       R402H16                     R433
63.R0034.1DL       R402H16                     R434
64.10006.6DL       R402H14                     R435
64.10006.6DL       R402H14                     R436
64.20035.6DL       R402H16                     R437
64.20035.6DL       R402H16                     R438
64.20035.6DL       R402H16                     R439
64.2R205.55L       R603H22                     R440
64.20035.6DL       R402H16                     R441
63.R0034.1DL       R402H16                     R442
64.47015.6DL       R402H16                     R443
63.R0034.1DL       R402H16                     R444
64.10015.6DL       R402H16                     R445
63.R0034.1DL       R402H16                     R446
64.10015.6DL       R402H16                     R448
64.20035.6DL       R402H16                     R449
64.10015.6DL       R402H16                     R450
64.47015.6DL       R402H16                     R455
63.R0034.1DL       R402H16                     R461
64.20035.6DL       R402H16                     R470
64.10015.6DL       R402H16                     R471
64.10015.6DL       R402H16                     R472
63.R0034.1DL       R402H16                     R473
63.10034.1DL       R402H14                     R474
64.R0005.6DL       R402H16                     R475
64.R0005.6DL       R402H16                     R476
64.R0005.6DL       R402H16                     R477
64.R0005.6DL       R402H16                     R478
64.1R005.16L       R805H24                     R479
63.00000.00L       R603H22                     R480
63.00000.00L       R603H22                     R481
63.00000.00L       R603H22                     R482
64.10025.6DL       R402H16                     R483
64.10025.6DL       R402H16                     R484
64.69825.6DL       R402H16                     R485
63.R0034.1DL       R402H16                     R486
64.10025.6DL       R402H16                     R487
64.10025.6DL       R402H16                     R488
64.22105.6DL       R402H16                     R489
64.12115.6DL       R402H16                     R490
64.22105.6DL       R402H16                     R491
64.19125.6DL       R402H16                     R492
64.45305.6DL       R402H16                     R493
64.73215.6DL       R402H16                     R494
64.10035.6DL       R402H16                     R495
64.10035.6DL       R402H16                     R496
63.R0034.1DL       R402H16                     R497
63.R0034.1DL       R402H16                     R498
63.2R233.15L       R603H22                     R499
64.10025.6DL       R402H16                     R500
64.19625.6DL       R402H16                     R501
64.61935.6DL       R402H16                     R502
64.86635.6DL       R402H16                     R503
64.51025.6DL       R402H16                     R504
64.10035.6DL       R402H16                     R505
64.47535.6DL       R402H16                     R508
63.R0031.16L       R805H24                     R509
63.R0031.16L       R805H24                     R510
63.R0031.16L       R805H24                     R511
64.10R05.55L       R603H22                     R512
64.44225.6DL       R402H16                     R513
64.27015.6DL       R402H16                     R514
64.2R205.55L       R603H22                     R515
64.3R015.16L       R805H24                     R516
63.R0034.1DL       R402H16                     R517
64.10025.6DL       R402H16                     R518
64.10R05.6DL       R402H14                     R519
64.10R05.6DL       R402H14                     R520
64.38325.6DL       R402H16                     R521
64.10R05.6DL       R402H14                     R522
64.10R05.6DL       R402H14                     R523
63.R0034.1DL       R402H16                     R524
63.R0034.1DL       R402H16                     R525
64.10R05.16L       R805H24                     R526
63.R0031.16L       R805H24                     R527
64.10025.6DL       R402H16                     R528
63.R0034.1DL       R402H16                     R529
63.10234.1DL       R402H16                     R531
64.10035.6DL       R402H16                     R532
63.R0034.1DL       R402H16                     R533
63.R0034.1DL       R402H16                     R534
63.R0034.1DL       R402H16                     R535
63.R0034.1DL       R402H16                     R536
63.R0034.1DL       R402H16                     R538
63.R0034.1DL       R402H16                     R539
63.R0034.1DL       R402H16                     R540
63.R0034.1DL       R402H16                     R541
63.R0034.1DL       R402H16                     R542
64.11025.6DL       R402H16                     R543
63.R0034.1DL       R402H16                     R544
63.R0034.1DL       R402H16                     R545
64.47015.6DL       R402H16                     R546
64.47015.6DL       R402H16                     R547
64.45325.6DL       R402H16                     R548
64.47015.6DL       R402H16                     R549
64.49925.6DL       R402H16                     R550
64.49925.6DL       R402H16                     R551
63.R0034.1DL       R402H16                     R552
63.R0034.1DL       R402H16                     R553
64.10025.6DL       R402H16                     R555
63.R0034.1DL       R402H16                     R556
64.10025.6DL       R402H16                     R557
63.R0034.1DL       R402H16                     R558
64.10025.6DL       R402H16                     R559
64.10025.6DL       R402H16                     R560
64.10025.6DL       R402H16                     R561
64.10025.6DL       R402H16                     R562
64.10025.6DL       R402H16                     R563
64.10025.6DL       R402H16                     R564
64.10025.6DL       R402H16                     R565
64.10025.6DL       R402H16                     R566
64.10025.6DL       R402H16                     R567
64.10025.6DL       R402H16                     R569
63.R0034.1DL       R402H16                     R572
63.R0034.1DL       R402H16                     R573
63.R0034.1DL       R402H16                     R574
64.10025.6DL       R402H16                     R575
63.R0034.1DL       R402H16                     R576
64.10025.6DL       R402H16                     R577
63.R0034.1DL       R402H16                     R578
63.R0034.1DL       R402H16                     R579
64.10025.6DL       R402H16                     R580
63.R0034.1DL       R402H16                     R581
63.R0034.1DL       R402H16                     R582
63.R0034.1DL       R402H16                     R583
63.R0034.1DL       R402H16                     R584
63.R0034.1DL       R402H16                     R585
64.10025.6DL       R402H16                     R587
64.47015.6DL       R402H16                     R599
63.R0034.1DL       R402H16                     R601
64.47015.6DL       R402H16                     R602
63.R0034.1DL       R402H16                     R603
64.47015.6DL       R402H16                     R604
64.47015.6DL       R402H16                     R605
64.10025.6DL       R402H16                     R606
63.10234.1DL       R402H16                     R607
64.10025.6DL       R402H16                     R608
63.75334.1DL       R402H16                     R609
64.10025.6DL       R402H16                     R688
63.R0034.1DL       R402H16                     R691
63.R0034.1DL       R402H16                     R692
64.10025.6DL       R402H16                     R693
64.2R205.16L       R805H24                     R694
ZZ.00PAD.QL1       HOLE709R146-3P-S2           RHOLE1
79.47719.2BL       CT7343H83                   TC1
79.47719.2BL       CT7343H83                   TC2
79.47719.2BL       CT7343H83                   TC3
077.51571.0001     CT7343H83                   TC4
077.51571.0001     CT7343H83                   TC5
79.47719.2BL       CT7343H83                   TC6
79.47719.2BL       CT7343H83                   TC7
ZZ.PAD28.XXX       TPAD28                      TP15
ZZ.PAD28.XXX       TPAD28                      TP16
ZZ.PAD28.XXX       TPAD28                      TP17
ZZ.PAD28.XXX       TPAD28                      TP18
ZZ.PAD28.XXX       TPAD28                      TP19
ZZ.PAD28.XXX       TPAD28                      TP20
ZZ.PAD28.XXX       TPAD28                      TP21
ZZ.PAD28.XXX       TPAD28                      TP22
ZZ.PAD28.XXX       TPAD28                      TP23
ZZ.PAD28.XXX       TPAD28                      TP24
ZZ.PAD28.XXX       TPAD28                      TP25
ZZ.PAD28.XXX       TPAD28                      TP26
ZZ.PAD28.XXX       TPAD28                      TP27
ZZ.PAD28.XXX       TPAD28                      TP28
ZZ.PAD28.XXX       TPAD28                      TP35
ZZ.PAD28.XXX       TPAD28                      TP36
ZZ.PAD28.XXX       TPAD28                      TP37
ZZ.PAD28.XXX       TPAD28                      TP38
ZZ.PAD28.XXX       TPAD28                      TP39
ZZ.PAD28.XXX       TPAD28                      TP40
ZZ.PAD28.XXX       TPAD28                      TP41
ZZ.PAD28.XXX       TPAD28                      TP42
ZZ.PAD28.XXX       TPAD28                      TP43
ZZ.PAD28.XXX       TPAD28                      TP44
ZZ.PAD28.XXX       TPAD28                      TP45
ZZ.PAD28.XXX       TPAD28                      TP46
ZZ.PAD28.XXX       TPAD28                      TP47
ZZ.PAD28.XXX       TPAD28                      TP48
ZZ.PAD28.XXX       TPAD28                      TP49
ZZ.PAD28.XXX       TPAD28                      TP50
ZZ.PAD28.XXX       TPAD28                      TP51
ZZ.PAD28.XXX       TPAD28                      TP52
ZZ.PAD28.XXX       TPAD28                      TP53
ZZ.PAD28.XXX       TPAD28                      TP54
ZZ.PAD28.XXX       TPAD28                      TP55
ZZ.PAD28.XXX       TPAD28                      TP56
ZZ.PAD28.XXX       TPAD28                      TP57
ZZ.PAD28.XXX       TPAD28                      TP58
ZZ.PAD28.XXX       TPAD28                      TP59
ZZ.PAD28.XXX       TPAD28                      TP60
ZZ.PAD28.XXX       TPAD28                      TP61
ZZ.PAD28.XXX       TPAD28                      TP62
ZZ.PAD28.XXX       TPAD28                      TP63
ZZ.PAD28.XXX       TPAD28                      TP64
ZZ.PAD28.XXX       TPAD28                      TP65
ZZ.PAD28.XXX       TPAD28                      TP66
ZZ.PAD28.XXX       TPAD28                      TP67
ZZ.PAD28.XXX       TPAD28                      TP68
ZZ.PAD28.XXX       TPAD28                      TP69
ZZ.PAD28.XXX       TPAD28                      TP70
ZZ.PAD28.XXX       TPAD28                      TP71
ZZ.PAD28.XXX       TPAD28                      TP72
ZZ.PAD28.XXX       TPAD28                      TP73
ZZ.PAD28.XXX       TPAD28                      TP74
ZZ.PAD28.XXX       TPAD28                      TP75
ZZ.PAD28.XXX       TPAD28                      TP76
ZZ.PAD28.XXX       TPAD28                      TP77
ZZ.PAD28.XXX       TPAD28                      TP78
ZZ.PAD28.XXX       TPAD28                      TP79
ZZ.PAD28.XXX       TPAD28                      TP80
ZZ.PAD28.XXX       TPAD28                      TP81
ZZ.PAD28.XXX       TPAD28                      TP82
ZZ.PAD28.XXX       TPAD28                      TP83
ZZ.PAD28.XXX       TPAD28                      TP84
ZZ.PAD28.XXX       TPAD28                      TP85
ZZ.PAD28.XXX       TPAD28                      TP86
ZZ.PAD28.XXX       TPAD28                      TP87
ZZ.PAD28.XXX       TPAD28                      TP88
ZZ.PAD28.XXX       TPAD28                      TP89
ZZ.PAD28.XXX       TPAD28                      TP90
ZZ.PAD28.XXX       TPAD28                      TP91
ZZ.PAD28.XXX       TPAD28                      TP92
ZZ.PAD28.XXX       TPAD28                      TP93
ZZ.PAD28.XXX       TPAD28                      TP94
ZZ.PAD28.XXX       TPAD28                      TP95
ZZ.PAD28.XXX       TPAD28                      TP96
ZZ.PAD28.XXX       TPAD28                      TP97
ZZ.PAD28.XXX       TPAD28                      TP98
ZZ.PAD28.XXX       TPAD28                      TP99
ZZ.PAD28.XXX       TPAD28                      TP100
ZZ.PAD28.XXX       TPAD28                      TP101
ZZ.PAD28.XXX       TPAD28                      TP102
ZZ.PAD28.XXX       TPAD28                      TP103
ZZ.PAD28.XXX       TPAD28                      TP104
ZZ.PAD28.XXX       TPAD28                      TP105
ZZ.PAD28.XXX       TPAD28                      TP106
ZZ.PAD28.XXX       TPAD28                      TP107
ZZ.PAD28.XXX       TPAD28                      TP108
ZZ.PAD28.XXX       TPAD28                      TP109
ZZ.PAD28.XXX       TPAD28                      TP110
ZZ.PAD28.XXX       TPAD28                      TP111
ZZ.PAD28.XXX       TPAD28                      TP112
ZZ.PAD28.XXX       TPAD28                      TP113
ZZ.PAD28.XXX       TPAD28                      TP114
ZZ.PAD28.XXX       TPAD28                      TP115
ZZ.PAD28.XXX       TPAD28                      TP116
ZZ.PAD28.XXX       TPAD28                      TP117
ZZ.PAD28.XXX       TPAD28                      TP118
ZZ.PAD28.XXX       TPAD28                      TP119
ZZ.PAD28.XXX       TPAD28                      TP120
ZZ.PAD28.XXX       TPAD28                      TP121
ZZ.PAD28.XXX       TPAD28                      TP122
ZZ.PAD28.XXX       TPAD28                      TP123
ZZ.PAD28.XXX       TPAD28                      TP124
ZZ.PAD28.XXX       TPAD28                      TP125
ZZ.PAD28.XXX       TPAD28                      TP126
ZZ.PAD28.XXX       TPAD28                      TP127
ZZ.PAD28.XXX       TPAD28                      TP128
ZZ.PAD28.XXX       TPAD28                      TP129
ZZ.PAD28.XXX       TPAD28                      TP130
ZZ.PAD28.XXX       TPAD28                      TP131
ZZ.PAD28.XXX       TPAD28                      TP132
ZZ.PAD28.XXX       TPAD28                      TP133
ZZ.PAD28.XXX       TPAD28                      TP134
ZZ.PAD28.XXX       TPAD28                      TP135
ZZ.PAD28.XXX       TPAD28                      TP136
ZZ.PAD28.XXX       TPAD28                      TP137
ZZ.PAD28.XXX       TPAD28                      TP138
ZZ.PAD28.XXX       TPAD28                      TP139
ZZ.PAD28.XXX       TPAD28                      TP140
ZZ.PAD28.XXX       TPAD28                      TP141
ZZ.PAD28.XXX       TPAD28                      TP142
ZZ.PAD28.XXX       TPAD28                      TP143
ZZ.PAD28.XXX       TPAD28                      TP144
ZZ.PAD28.XXX       TPAD28                      TP145
ZZ.PAD28.XXX       TPAD28                      TP146
ZZ.PAD28.XXX       TPAD28                      TP147
ZZ.PAD28.XXX       TPAD28                      TP148
ZZ.PAD28.XXX       TPAD28                      TP149
ZZ.PAD28.XXX       TPAD28                      TP150
ZZ.PAD28.XXX       TPAD28                      TP151
ZZ.PAD28.XXX       TPAD28                      TP152
ZZ.PAD28.XXX       TPAD28                      TP153
ZZ.PAD28.XXX       TPAD28                      TP154
ZZ.PAD28.XXX       TPAD28                      TP157
ZZ.PAD28.XXX       TPAD28                      TP158
ZZ.PAD28.XXX       TPAD28                      TP159
ZZ.PAD28.XXX       TPAD28                      TP160
ZZ.PAD28.XXX       TPAD28                      TP161
ZZ.PAD28.XXX       TPAD28                      TP163
ZZ.PAD28.XXX       TPAD28                      TP164
ZZ.PAD28.XXX       TPAD28                      TP165
ZZ.PAD28.XXX       TPAD28                      TP166
ZZ.PAD28.XXX       TPAD28                      TP167
ZZ.PAD28.XXX       TPAD28                      TP168
ZZ.PAD28.XXX       TPAD28                      TP169
71.03X48.00U       BGA1020C33H83               U1
19-000387$AA       BGA896D25H78                U2
74.74801.A33       QFN20-1G3D15H40             U4
074.01278.0A7Z     QFN32-G3D45-UH32            U5
74.00235.033       QFN19-1H40                  U6
74.78M05.03C       SOT-223H67                  U7
74.51219.A73       QFN16-G1D8-UH32             U8
73.01G07.EHH       SC70-5H44                   U9
74.53318.073       DFN22G6050-G6133H60         U10
74.53318.073       DFN22G6050-G6133H60         U11
73.8T245.B29       TVSOP24H48                  U12
72.29128.Z09       TSOP56-1H48                 U13
73.8T245.B29       TVSOP24H48                  U14
72.24C64.I01       SOIC8H69                    U15
074.03808.M001     SOT-6H58                    U16
72.29128.Z09       TSOP56-1H48                 U18
73.00102.007       SSOIC8-4H36                 U20
73.00102.007       SSOIC8-4H36                 U21
73.00102.007       SSOIC8-4H36                 U22
074.03808.M001     SOT-6H58                    U23
73.8T245.B29       TVSOP24H48                  U24
74.01015.049       MSOP10H44                   U25
74.01015.049       MSOP10H44                   U26
72.24C64.I01       SOIC8H69                    U27
072.02464.0001     SOIC8H69                    U29
74.00075.B79       MSOP8-1H44                  U30
71.09306.B0I       SSOIC8H52                   U35
71.09306.B0I       SSOIC8H52                   U36
71.09306.B0I       SSOIC8H52                   U37
71.09306.B0I       SSOIC8H52                   U38
71.09306.B0I       SSOIC8H52                   U39
71.09306.B0I       SSOIC8H52                   U40
71.09306.B0I       SSOIC8H52                   U41
73.01G11.AHH       UMT6H44                     U42
71.09306.B0I       SSOIC8H52                   U46
73.1G126.DHG       SC70-5H44                   U47
73.1G126.DHG       SC70-5H44                   U48
73.1G126.DHG       SC70-5H44                   U49
73.1G126.DHG       SC70-5H44                   U50
073.03166.000B     SC70-5H44                   U118
073.03166.000B     SC70-5H44                   U119
073.03166.000B     SC70-5H44                   U120
073.03166.000B     SC70-5H44                   U122
ZZ.00PAD.MP1       VIA-PCIE-4P-368076          VIA1
ZZ.00PAD.MP1       VIA-PCIE-4P-368076          VIA2
ZZ.00PAD.MP1       VIA-PCIE-4P-368076          VIA3
ZZ.00PAD.MP1       VIA-PCIE-4P-368076          VIA4
ZZ.00PAD.MP1       VIA-PCIE-4P-368076          VIA5
ZZ.00PAD.MP1       VIA-PCIE-4P-368076          VIA6
ZZ.00PAD.MP1       VIA-PCIE-4P-368076          VIA7
ZZ.00PAD.MP1       VIA-PCIE-4P-368076          VIA8
ZZ.00PAD.NA1       VIA-PCIE-4P-409091          VIA9
ZZ.00PAD.NA1       VIA-PCIE-4P-409091          VIA10
ZZ.00PAD.NA1       VIA-PCIE-4P-409091          VIA11
ZZ.00PAD.NA1       VIA-PCIE-4P-409091          VIA12
ZZ.00PAD.NA1       VIA-PCIE-4P-409091          VIA13
ZZ.00PAD.NA1       VIA-PCIE-4P-409091          VIA14
ZZ.00PAD.NA1       VIA-PCIE-4P-409091          VIA15
ZZ.00PAD.NA1       VIA-PCIE-4P-409091          VIA16
ZZ.00PAD.NA1       VIA-PCIE-4P-409091          VIA17
ZZ.00PAD.NA1       VIA-PCIE-4P-409091          VIA18
ZZ.00PAD.NA1       VIA-PCIE-4P-409091          VIA19
ZZ.00PAD.NA1       VIA-PCIE-4P-409091          VIA20
ZZ.00PAD.NA1       VIA-PCIE-4P-409091          VIA21
ZZ.00PAD.NA1       VIA-PCIE-4P-409091          VIA22
ZZ.00PAD.NA1       VIA-PCIE-4P-409091          VIA23
ZZ.00PAD.NA1       VIA-PCIE-4P-409091          VIA24
ZZ.00PAD.NB1       VIA-PCIE-4P-394076          VIA25
ZZ.00PAD.NB1       VIA-PCIE-4P-394076          VIA26
ZZ.00PAD.NB1       VIA-PCIE-4P-394076          VIA27
ZZ.00PAD.NB1       VIA-PCIE-4P-394076          VIA28
082.30005.0311     SMD-OSC38H20                X1
082.30005.0311     SMD-OSC38H20                X2

EOS

POSITION

BLED1      3214.59     3016.95      90.000    TOP
C1         5364.00     3172.00     270.000    BOT
C2         5364.00     3194.00     270.000    BOT
C3         5363.00     3112.00     270.000    BOT
C4         5363.00     3134.00     270.000    BOT
C5         5362.00     3051.00     270.000    BOT
C6         5362.00     3073.00     270.000    BOT
C7         5361.00     2976.00     270.000    BOT
C8         5361.00     2998.00     270.000    BOT
C9         5410.00     2937.00     270.000    BOT
C10        5410.00     2915.00     270.000    BOT
C11        5412.00     2874.00     270.000    BOT
C12        5412.00     2852.00     270.000    BOT
C13        5412.00     2813.00     270.000    BOT
C14        5412.00     2791.00     270.000    BOT
C15        5412.00     2752.00     270.000    BOT
C16        5412.00     2730.00     270.000    BOT
C17        5412.00     2691.00     270.000    BOT
C18        5412.00     2669.00     270.000    BOT
C19        5412.00     2631.00     270.000    BOT
C20        5412.00     2609.00     270.000    BOT
C21        5295.01     2561.67     270.000    BOT
C22        5295.01     2539.67     270.000    BOT
C23        5341.20     2413.57     180.000    BOT
C24        5319.20     2413.57     180.000    BOT
C25        5330.93     2219.67     180.000    BOT
C26        5308.93     2219.67     180.000    BOT
C27        5269.00     1748.00     180.000    BOT
C28        5247.00     1748.00     180.000    BOT
C29        5172.55     1747.22     180.000    BOT
C30        5150.55     1747.22     180.000    BOT
C31        5071.00     1609.00     180.000    BOT
C32        5048.00     1609.00     180.000    BOT
C33        5621.19     2511.46     270.000    TOP
C34        5621.19     2534.46     270.000    TOP
C35        5604.40     2435.59     270.000    TOP
C36        5604.40     2458.59     270.000    TOP
C37        5613.30     2359.88     270.000    TOP
C38        5613.30     2382.88     270.000    TOP
C39        5629.65     2272.50     270.000    TOP
C40        5629.65     2295.50     270.000    TOP
C41        5241.95     1759.96     180.000    TOP
C42        5264.95     1759.96     180.000    TOP
C43        5140.70     1760.54     180.000    TOP
C44        5163.70     1760.54     180.000    TOP
C45        5039.45     1761.12     180.000    TOP
C46        5062.45     1761.12     180.000    TOP
C47        4941.99     1761.70     180.000    TOP
C48        4964.99     1761.70     180.000    TOP
C49        5018.00     1554.00     180.000    BOT
C50        4995.00     1554.00     180.000    BOT
C51        4944.00     1554.00     180.000    BOT
C52        4921.00     1554.00     180.000    BOT
C53        4874.00     1554.00     180.000    BOT
C54        4851.00     1554.00     180.000    BOT
C55        4804.00     1554.00     180.000    BOT
C56        4781.00     1554.00     180.000    BOT
C57        4727.00     1741.00     180.000    BOT
C58        4705.00     1741.00     180.000    BOT
C59        4667.00     1741.00     180.000    BOT
C60        4645.00     1741.00     180.000    BOT
C61        4607.00     1741.00     180.000    BOT
C62        4585.00     1741.00     180.000    BOT
C63        4547.00     1741.00     180.000    BOT
C64        4525.00     1741.00     180.000    BOT
C65        4487.00     1741.00     180.000    BOT
C66        4465.00     1741.00     180.000    BOT
C67        4427.00     1741.00     180.000    BOT
C68        4405.00     1741.00     180.000    BOT
C69        4367.00     1741.00     180.000    BOT
C70        4345.00     1741.00     180.000    BOT
C71        4307.00     1741.00     180.000    BOT
C72        4247.00     1741.00     180.000    BOT
C73        4285.00     1741.00     180.000    BOT
C74        4225.00     1741.00     180.000    BOT
C75        4187.00     1741.00     180.000    BOT
C76        4165.00     1741.00     180.000    BOT
C77        4105.00     1741.00     180.000    BOT
C78        4127.00     1741.00     180.000    BOT
C79        4067.00     1741.00     180.000    BOT
C80        4045.00     1741.00     180.000    BOT
C81        4007.00     1741.00     180.000    BOT
C82        3985.00     1741.00     180.000    BOT
C83        3947.00     1741.00     180.000    BOT
C84        3925.00     1741.00     180.000    BOT
C85        3887.00     1741.00     180.000    BOT
C86        3865.00     1741.00     180.000    BOT
C87        3827.00     1741.00     180.000    BOT
C88        3799.11     1982.92      90.000    BOT
C89        3805.00     1741.00     180.000    BOT
C90        3799.11     2005.92      90.000    BOT
C91        3799.11     2037.92      90.000    BOT
C92        3799.11     2060.92      90.000    BOT
C93        3799.11     2115.92      90.000    BOT
C94        3799.11     2092.92      90.000    BOT
C95        3799.11     2147.92      90.000    BOT
C96        3799.11     2170.92      90.000    BOT
C97        2855.00      573.18     180.000    BOT
C98        2817.00      573.18     180.000    BOT
C101       2635.12      596.18      90.000    BOT
C104       6452.48      460.95       0.000    BOT
C108        303.00     2175.00     270.000    TOP
C109       7163.98     4597.29      90.000    TOP
C110       3485.97     2188.40     180.000    TOP
C111       3448.91     2078.40       0.000    TOP
C112       3583.00     3340.00      90.000    TOP
C113       3525.00     3475.00     270.000    TOP
C114       3789.71     3328.10     270.000    BOT
C115        598.26     2501.39     270.000    TOP
C116       3404.00     2858.00     270.000    BOT
C117       3143.00     2901.00     270.000    BOT
C118       4921.32     2985.73     180.000    BOT
C119       4223.23     2858.48       0.000    BOT
C120       4183.23     2858.48       0.000    BOT
C121       4694.90     2937.72     180.000    BOT
C122       4656.40     2937.72     180.000    BOT
C123       4704.90     2833.00       0.000    BOT
C124       4745.20     2845.00       0.000    BOT
C125       4784.00     2845.00       0.000    BOT
C126       4273.00     2579.00     270.000    BOT
C127       4512.00     2830.00       0.000    BOT
C128       4280.00     2835.00       0.000    BOT
C129       4276.35     2408.81       0.000    BOT
C130       4379.00     2831.00       0.000    BOT
C131       4626.00     2993.00     180.000    BOT
C132       3955.00     2342.00       0.000    BOT
C133       4535.00     2830.00       0.000    BOT
C134       4558.00     2830.02       0.000    BOT
C135       4354.00     2831.00       0.000    BOT
C136       3958.00     2303.00     270.000    BOT
C137       5135.00     3100.00     270.000    BOT
C138       4587.00     2992.00     180.000    BOT
C139       3955.00     2421.00       0.000    BOT
C140       4633.00     2831.00       0.000    BOT
C141       4466.68     2971.55      90.000    BOT
C142       4465.00     2831.00       0.000    BOT
C143       4658.00     2831.00       0.000    BOT
C144       4745.00     3010.00     180.000    BOT
C145       4511.00     3168.00     180.000    BOT
C146       5127.00     3185.00     180.000    BOT
C147       4863.08     3171.42     180.000    BOT
C148       4303.00     2835.00       0.000    BOT
C149       4586.67     3170.05     180.000    BOT
C150       4437.00     2831.00       0.000    BOT
C151       4981.00     3090.20     270.000    BOT
C152       4113.98     2305.00       0.000    BOT
C153       4581.00     2830.00       0.000    BOT
C154       4079.00     2509.00     270.000    BOT
C155       4075.00     2382.00       0.000    BOT
C156       4154.00     3134.00       0.000    BOT
C157       4273.00     2540.00     270.000    BOT
C158       4620.00     2612.50       0.000    BOT
C159       4460.00     2538.50       0.000    BOT
C160       4619.50     2538.50       0.000    BOT
C161       4349.18     2578.27     270.000    BOT
C162       4520.50     2612.50       0.000    BOT
C163       4475.00     2771.00     180.000    BOT
C164       4539.50     2538.50       0.000    BOT
C165       4460.00     2703.00       0.000    BOT
C166       4515.00     2703.00       0.000    BOT
C167       4595.00     2612.50       0.000    BOT
C168       4540.00     2703.00       0.000    BOT
C169       4434.00     2612.50       0.000    BOT
C170       4435.00     2538.50       0.000    BOT
C171       4500.00     2771.00     180.000    BOT
C172       4545.50     2612.50       0.000    BOT
C173       4587.00     2771.00     180.000    BOT
C174       4594.50     2538.50       0.000    BOT
C175       4514.50     2538.50       0.000    BOT
C176       4547.00     2771.00     180.000    BOT
C177       4435.00     2703.00       0.000    BOT
C178       4620.00     2703.00       0.000    BOT
C179       4595.00     2703.00       0.000    BOT
C180       4459.00     2612.50       0.000    BOT
C181       4400.00     2771.00     180.000    BOT
C182       4425.00     2771.00     180.000    BOT
C183       4675.37     2701.96       0.000    BOT
C184       4350.18     2531.01     270.000    BOT
C185       4675.47     2612.50       0.000    BOT
C186       4675.34     2540.00       0.000    BOT
C187       4625.53     2770.70     180.000    BOT
C188       4689.68     2772.74     180.000    BOT
C189       4666.58     2772.74     180.000    BOT
C190       4341.67     2733.53     270.000    BOT
C192       3628.10     2521.40       0.000    BOT
C193       3673.40     2521.40       0.000    BOT
C194       4005.00     2264.00      90.000    BOT
C195       3950.00     2263.00     270.000    BOT
C196       3628.68     2802.87       0.000    BOT
C197       3673.68     2802.87       0.000    BOT
C198       4075.00     2550.00     180.000    BOT
C199       4114.00     2550.00     180.000    BOT
C200       3628.68     2662.41     180.000    BOT
C201       3673.68     2662.41     180.000    BOT
C202       4114.36     2450.00       0.000    BOT
C203       4185.00     2540.00     270.000    BOT
C204       3626.89     2943.41     180.000    BOT
C205       3698.89     2944.41     180.000    BOT
C206       4232.97     2590.00     180.000    BOT
C207       4193.00     2590.00     180.000    BOT
C208       3626.77     3080.62       0.000    BOT
C209       3671.77     3083.62       0.000    BOT
C210       4120.00     2640.00       0.000    BOT
C211       4145.00     2640.00       0.000    BOT
C212       6690.00     2480.00     180.000    BOT
C214       4744.00     2785.00     270.000    BOT
C215       4745.00     2706.00     270.000    BOT
C216       4744.00     2625.00     270.000    BOT
C217       4747.00     2492.00     270.000    BOT
C218       4746.00     2548.00     270.000    BOT
C219       4755.00     2420.79       0.000    BOT
C220       4595.00     2420.79       0.000    BOT
C221       4263.00     2475.00     180.000    BOT
C222       4515.00     2420.79       0.000    BOT
C223       4448.50     2420.79       0.000    BOT
C224       4380.00     2420.79       0.000    BOT
C225       4304.70     2420.79       0.000    BOT
C226       4676.00     2420.79       0.000    BOT
C227       2900.00     1420.00       0.000    BOT
C228       3005.00     1415.00       0.000    BOT
C229       5038.22     2224.50     270.000    BOT
C230       4821.82     2626.95     270.000    BOT
C231       4434.00     2263.00       0.000    BOT
C232       5094.38     2232.90      90.000    BOT
C233       4515.00     2105.00     180.000    BOT
C234       2900.00     2450.00     180.000    BOT
C235       3005.00     2445.00     180.000    BOT
C236       5094.38     2149.71      90.000    BOT
C237       4518.40     2340.50       0.000    BOT
C238       4670.50     2263.00       0.000    BOT
C239       4285.50     2340.50       0.000    BOT
C240       4360.00     2340.50       0.000    BOT
C241       2900.00     2035.00     180.000    BOT
C242       3005.00     2020.00     180.000    BOT
C243       4862.50     2863.50     180.000    BOT
C244       4903.00     2893.00     270.000    BOT
C245       4893.00     2697.00     270.000    BOT
C246       4822.00     2539.00     270.000    BOT
C247       4439.00     2340.50       0.000    BOT
C248       2900.00     2255.00       0.000    BOT
C249       3010.00     2260.00       0.000    BOT
C250       4247.45     2335.50     270.000    BOT
C251       4779.00     2340.50       0.000    BOT
C252       4901.50     2382.00      90.000    BOT
C253       4232.00     2263.00       0.000    BOT
C254       4516.50     2263.00       0.000    BOT
C255       2895.00     1420.00       0.000    TOP
C256       2965.00     1415.00       0.000    TOP
C257       5038.22     2263.50     270.000    BOT
C258       4893.00     2500.00     270.000    BOT
C259       4774.00     2263.00       0.000    BOT
C260       4852.50     2263.00       0.000    BOT
C261       4277.00     2263.00       0.000    BOT
C262       2895.00     2450.00     180.000    TOP
C263       2965.00     2451.50     180.000    TOP
C264       5094.38     2337.48      90.000    BOT
C265       4591.50     2263.00       0.000    BOT
C266       4541.50     2263.00       0.000    BOT
C267       4749.00     2263.00       0.000    BOT
C268       4695.50     2263.00       0.000    BOT
C269       4822.00     2421.00     270.000    BOT
C270       2895.00     2035.00     180.000    TOP
C271       5094.38     2310.89      90.000    BOT
C272       5038.22     2342.19     270.000    BOT
C273       5038.22     2145.76     270.000    BOT
C274       4941.00     2907.00     180.000    BOT
C275       2965.00     2031.00     180.000    TOP
C276       4754.00     2340.50       0.000    BOT
C277       2895.00     1840.00       0.000    TOP
C278       4902.00     2274.00      90.000    BOT
C279       4910.50     2775.00      90.000    BOT
C280       4822.00     2776.00     270.000    BOT
C281       4901.50     2106.50      90.000    BOT
C282       4824.02     2340.78       0.000    BOT
C283       2895.00     1620.00     180.000    TOP
C284       4464.00     2340.50       0.000    BOT
C285       4822.00     2578.00     270.000    BOT
C286       4902.17     2342.08      90.000    BOT
C287       4826.00     2852.00     270.000    BOT
C288       2970.00     1620.00     180.000    TOP
C289       4960.59     2047.07       0.000    BOT
C290       2895.00     2255.00       0.000    TOP
C291       4701.00     2340.50       0.000    BOT
C292       5060.00     2625.00     270.000    BOT
C293       4902.00     2299.00      90.000    BOT
C294       4247.45     2310.50     270.000    BOT
C295       2970.00     2253.50       0.000    TOP
C296       2965.00     1833.00       0.000    TOP
C297       5094.38     2174.56      90.000    BOT
C298       2900.00     1840.00       0.000    BOT
C299       5094.38     2257.90      90.000    BOT
C300       4910.00     2656.00      90.000    BOT
C301       4822.00     2460.00     270.000    BOT
C302       5038.22     2185.00     270.000    BOT
C303       3005.00     1835.00       0.000    BOT
C304       4893.00     2539.00     270.000    BOT
C305       2900.00     1620.00     180.000    BOT
C306       4910.00     2736.50      90.000    BOT
C307       4893.00     2619.50     270.000    BOT
C308       5070.86     2894.38     270.000    BOT
C309       5038.22     2302.91     270.000    BOT
C310       3010.00     1620.00     180.000    BOT
C311       6493.07      810.36       0.000    BOT
C312       6518.07      810.36       0.000    BOT
C313       6560.80      809.96       0.000    BOT
C314       6585.80      809.96       0.000    BOT
C315       6652.85      827.04       0.000    BOT
C316       6675.50      826.94       0.000    BOT
C317       6729.26      822.30       0.000    BOT
C318       6753.26      822.30       0.000    BOT
C319       6812.83      822.29       0.000    BOT
C320       6835.63      822.30       0.000    BOT
C321       6891.49      824.98       0.000    BOT
C322       6913.82      824.99       0.000    BOT
C323       7024.41      810.23      90.000    BOT
C324       7024.44      832.70      90.000    BOT
C325       7136.60      837.60      90.000    BOT
C326       7136.59      859.92      90.000    BOT
C327       5718.47     1298.41     102.000    TOP
C328       5723.25     1275.91     102.000    TOP
C329       5829.51     1406.59     102.000    TOP
C330       5834.29     1384.10     102.000    TOP
C331       5899.12     1518.37     102.000    TOP
C332       5903.90     1495.88     102.000    TOP
C333       5805.91     1606.65     102.000    TOP
C334       6280.00     1665.00      90.000    TOP
C335       6200.00     1665.00     270.000    TOP
C336       5810.69     1584.16     102.000    TOP
C337       5846.84     1764.91     102.000    TOP
C338       5851.62     1742.41     102.000    TOP
C339       5757.87     1852.00     102.000    TOP
C340       5762.65     1829.51     102.000    TOP
C341       5799.89     2009.42     102.000    TOP
C342       5804.67     1986.93     102.000    TOP
C343       5839.18     2165.25     102.000    TOP
C344       5843.97     2142.76     102.000    TOP
C345       8045.00     1803.30     180.000    BOT
C346       8006.00     1803.30       0.000    BOT
C347       1689.38     4258.70     270.000    BOT
C348       1689.38     4328.70     270.000    BOT
C349       7971.55     2952.67     180.000    TOP
C350       8053.00     2690.00     180.000    TOP
C351       6565.00     2520.00      90.000    BOT
C352       6565.00     2440.00      90.000    BOT
C353       6560.00     2347.00      90.000    BOT
C354       6562.00     2384.00      90.000    BOT
C355       6070.26     2524.52     270.000    BOT
C356       6070.26     2444.52     270.000    BOT
C357       6068.26     2386.52     270.000    BOT
C358       6067.26     2349.52     270.000    BOT
C359       6215.26     2524.52      90.000    BOT
C360       6215.26     2444.52      90.000    BOT
C361       6210.26     2386.52      90.000    BOT
C362       6210.26     2349.52      90.000    BOT
C363       7881.07     1253.93       0.000    BOT
C364       7815.07     1255.93       0.000    BOT
C365       7754.07     1256.93       0.000    BOT
C366       7716.07     1256.93       0.000    BOT
C367       6420.00     2520.00     270.000    BOT
C368       6420.00     2440.00     270.000    BOT
C369       6425.00     2347.00     270.000    BOT
C370       6424.00     2384.00     270.000    BOT
C371       6317.81     1315.08     180.000    BOT
C372       6252.81     1315.08     180.000    BOT
C373       6429.00     1311.00      90.000    BOT
C374       6429.00     1488.00      90.000    BOT
C375       6429.50     1349.00      90.000    BOT
C376       6429.23     1449.11      90.000    BOT
C377       7765.00     1115.00     180.000    BOT
C378       7830.00     1115.00     180.000    BOT
C379       7720.00     1115.00     180.000    BOT
C380       6783.82     1287.35      90.000    BOT
C381       6624.00     1286.50     270.000    BOT
C382       6860.00     1287.00      90.000    BOT
C383       6903.00     3132.00     270.000    TOP
C384       6921.00     3063.00      90.000    TOP
C385       6921.00     3021.00      90.000    TOP
C386       6992.45     1127.75     180.000    BOT
C387       6503.83     1089.96     270.000    BOT
C388       6866.36     1343.46     180.000    BOT
C389       6775.05     1131.37     180.000    BOT
C390       6738.87     1342.86     180.000    BOT
C391       6806.71     1343.32     180.000    BOT
C392       6503.83     1112.96     270.000    BOT
C393       6711.97     1290.76      90.000    BOT
C394       7148.83     4030.14      90.000    TOP
C395       7148.83     4120.14      90.000    TOP
C396       6495.00     1258.50     270.000    BOT
C397       6494.54     1385.91     270.000    BOT
C398       6485.17     1161.14     270.000    BOT
C399       6485.17     1196.14     270.000    BOT
C400       6603.00     1518.00     180.000    BOT
C401       6673.00     1529.00     180.000    BOT
C402       6689.77     1353.18      90.000    BOT
C403       6689.18     1418.25      90.000    BOT
C404       6604.50     1341.00       0.000    BOT
C405       6967.61     1814.83     180.000    BOT
C406       6719.35     1873.51     270.000    BOT
C407       7061.95     1814.58     180.000    BOT
C408       6873.75     1815.04     180.000    BOT
C409       6716.62     1621.83     270.000    BOT
C410       6717.97     1779.41     270.000    BOT
C411       7064.62     1649.13      90.000    BOT
C412       6937.85     1563.36      90.000    BOT
C413       7000.50     1522.40      90.000    BOT
C414       6964.18     1403.04       0.000    BOT
C415       7000.23     1649.14      90.000    BOT
C416       6937.12     1648.65      90.000    BOT
C417       6937.00     1522.50      90.000    BOT
C418       6841.50     1711.30     270.000    BOT
C419       6901.00     1400.00       0.000    BOT
C420       7064.52     1522.35      90.000    BOT
C421       7000.44     1563.43      90.000    BOT
C422       6935.50     1711.50      90.000    BOT
C423       6878.98     1400.12       0.000    BOT
C424       7064.21     1564.19      90.000    BOT
C425       6842.00     1648.30     270.000    BOT
C426       6941.92     1403.03       0.000    BOT
C427       6841.50     1689.30     270.000    BOT
C428       6937.02     1458.15      90.000    BOT
C429       6937.00     1500.50      90.000    BOT
C430       6937.85     1585.36      90.000    BOT
C431       6937.12     1626.65      90.000    BOT
C432       6935.50     1689.50      90.000    BOT
C433       7000.52     1458.65      90.000    BOT
C434       7000.50     1500.40      90.000    BOT
C435       7000.44     1585.43      90.000    BOT
C436       7000.23     1627.14      90.000    BOT
C437       6776.47     1689.75     270.000    BOT
C438       6836.98     1400.05       0.000    BOT
C439       7064.52     1500.35      90.000    BOT
C440       7064.21     1586.19      90.000    BOT
C441       7064.62     1627.13      90.000    BOT
C442       6776.47     1711.75     270.000    BOT
C443       6842.00     1626.30     270.000    BOT
C444       6843.00     1573.50     270.000    BOT
C445       6844.00     1511.00     270.000    BOT
C446       6844.02     1453.15     270.000    BOT
C447       6749.52     1544.15     270.000    BOT
C448       6749.52     1509.15     270.000    BOT
C449       7074.10     1698.42      90.000    BOT
C450       6998.89     1698.42      90.000    BOT
C451       7067.88     1453.27      90.000    BOT
C452       6570.45     1840.73       0.000    BOT
C453       6568.75     1724.52       0.000    BOT
C454       7262.42     1827.95      90.000    BOT
C455       6569.44     1784.04       0.000    BOT
C456       6490.27     1904.77       0.000    BOT
C457       7262.42     1891.85      90.000    BOT
C458       7262.42     1700.65      90.000    BOT
C459       7213.20     1275.95       0.000    BOT
C460       6858.92     1897.43     270.000    BOT
C461       7262.42     1763.15      90.000    BOT
C462       7004.88     1898.06     270.000    BOT
C463       6588.37     1948.08      90.000    BOT
C464       6635.07     1881.80       0.000    BOT
C465       6714.52     2018.15     180.000    BOT
C466       6835.82     1954.95     270.000    BOT
C467       7250.22     1268.91      90.000    BOT
C468       7175.00     1250.00     270.000    BOT
C469       7120.00     1250.00     270.000    BOT
C470       7065.00     1250.00     270.000    BOT
C471       7013.00     1250.00     270.000    BOT
C472       7223.52     1320.25     270.000    BOT
C473       7221.00     1395.00     270.000    BOT
C474       7210.42     1451.65     270.000    BOT
C475       7210.42     1511.75     270.000    BOT
C476       7211.42     1577.15     270.000    BOT
C477       7219.00     1642.00     270.000    BOT
C478       7210.42     1700.65     270.000    BOT
C479       7210.42     1763.15     270.000    BOT
C480       7210.42     1827.95     270.000    BOT
C481       7210.42     1891.85     270.000    BOT
C482       7128.01     1952.67     270.000    BOT
C483       7214.00     1195.00      90.000    BOT
C484       6514.30     1724.34     180.000    BOT
C485       6995.00     1195.00     270.000    BOT
C486       7065.00     1195.00     270.000    BOT
C487       7135.00     1195.00     270.000    BOT
C488       6910.41     1897.23     270.000    BOT
C489       7262.42     1577.15      90.000    BOT
C490       7262.42     1511.75      90.000    BOT
C491       7262.42     1451.65      90.000    BOT
C492       7063.35     1897.77     270.000    BOT
C493       6678.43     1711.60     180.000    BOT
C494       6652.12     1957.05      90.000    BOT
C495       6728.92     1957.15      90.000    BOT
C496       6891.32     1980.95     180.000    BOT
C497       6978.52     1948.95     270.000    BOT
C498       7054.62     1953.65     270.000    BOT
C499       7278.55     1955.27      90.000    BOT
C500       7165.17     1875.23       0.000    BOT
C501       7201.33     1954.08     270.000    BOT
C502       6487.48      460.95       0.000    BOT
C503       5981.52     3645.41     180.000    TOP
C504       6245.70     3693.20      90.000    TOP
C505       6619.45      234.14      90.000    BOT
C506       5980.23     3882.11     180.000    TOP
C507       6252.70     3899.40      90.000    TOP
C508       7521.08     2801.64     270.000    TOP
C509       6522.48      460.95       0.000    BOT
C510       7784.40     2804.10       0.000    TOP
C511       1519.38     4238.70      90.000    BOT
C512       4597.00     2340.50       0.000    BOT
C513       4676.00     2340.50       0.000    BOT
C514       4893.00     2460.00     270.000    BOT
C515       3252.87     2771.70       0.000    BOT
C516       3217.87     2771.70       0.000    BOT
C517       3404.00     2777.70     270.000    BOT
C518       6310.00     3415.00      90.000    TOP
C519       6310.00     3375.00      90.000    TOP
C520       6310.00     3028.91      90.000    TOP
C521       6310.00     2990.91      90.000    TOP
C522        547.07     1755.52     270.000    TOP
C523        976.50     4526.50      90.000    TOP
C524       5955.00     3343.50     270.000    TOP
C525       6235.00     3276.54     270.000    TOP
C526       6310.00     3276.54      90.000    TOP
C527       1412.00     1958.00     180.000    TOP
C528        736.00     3182.00      90.000    TOP
C529        736.00     3217.00     270.000    TOP
C530        759.00     2917.00      90.000    TOP
C531       4822.00     2815.50     270.000    BOT
C532       5990.37     2840.17     270.000    TOP
C533       6310.00     2887.45      90.000    TOP
C534       6235.00     2887.45     270.000    TOP
C535       7574.88     2993.61       0.000    TOP
C536       4822.00     2499.50     270.000    BOT
C537       4310.50     2340.50       0.000    BOT
C538       4459.00     2263.00       0.000    BOT
C539       4385.00     2340.50       0.000    BOT
C540       4381.00     2263.00       0.000    BOT
C541        724.00     3380.00     270.000    TOP
C542        693.00     3738.00     180.000    TOP
C545        297.00     3378.00     270.000    TOP
C548        261.00     3733.52     180.000    TOP
C549       2336.00     3169.00      90.000    TOP
C550       2519.75     3169.67      90.000    TOP
C551       2508.45     2797.32     270.000    TOP
C552       2408.00     2797.00      90.000    TOP
C557       2713.65     3171.51      90.000    TOP
C558        507.00     3376.00     270.000    TOP
C559       2773.26     2783.33     270.000    TOP
C560        469.00     3732.33     180.000    TOP
C561       2162.00     3170.00      90.000    TOP
C562       2094.00     2878.00     270.000    TOP
C563       1519.38     4314.70      90.000    BOT
C564       1489.00     1958.00     180.000    TOP
C565        894.33     1217.88       0.000    TOP
C566       1049.30     1218.10       0.000    TOP
C570        898.95     3734.26     180.000    TOP
C571        934.95     3377.93     270.000    TOP
C574        485.00     1907.00     270.000    TOP
C575       5955.00     3379.00     270.000    TOP
C576       5936.70     4267.20     270.000    TOP
C577       7865.60     3264.30       0.000    TOP
C578       4893.00     2579.00     270.000    BOT
C579       4302.00     2263.00       0.000    BOT
C580       4356.00     2263.00       0.000    BOT
C581       4207.00     2263.00       0.000    BOT
C582       4910.50     2854.50      90.000    BOT
C583       4891.50     2815.00     270.000    BOT
C584       4543.40     2340.50       0.000    BOT
C585       4616.50     2263.00       0.000    BOT
C586       4822.00     2696.50     270.000    BOT
C587       4821.82     2651.95     270.000    BOT
C588       4622.00     2340.50       0.000    BOT
C589       4822.00     2736.00     270.000    BOT
C590       4822.00     2381.00     270.000    BOT
C591       4827.50     2263.00       0.000    BOT
C592       4892.50     2421.50     270.000    BOT
C594       1516.58     4182.70      90.000    BOT
C595       2322.00     3624.00     270.000    TOP
C596       7159.00     4894.00      90.000    TOP
C597       7299.00     4694.00     270.000    TOP
C598       2931.00     3283.00      90.000    TOP
C599       2789.00     3284.00     270.000    TOP
C600       6863.12     4802.21      90.000    BOT
C601       6917.35     4411.96      90.000    TOP
C602       7011.20     4356.20     180.000    TOP
C603       6728.00     4454.00       0.000    TOP
C604       1648.10     1454.31     180.000    TOP
C605       7131.50     4519.95       0.000    TOP
C606       6247.70     4582.30       0.000    TOP
C607       6275.70     4567.30     180.000    BOT
C608       5452.95     4713.83     270.000    BOT
C609       5190.12     4700.71     270.000    BOT
C610       5364.00     3172.00      90.000    TOP
C611       5883.50     4829.00      90.000    TOP
C612       1793.00     1145.00     270.000    TOP
C613       1894.13     1163.44     180.000    TOP
C614       2448.00     2385.00     270.000    BOT
C615       1952.13     1185.44     270.000    TOP
C616       1872.98     1453.80      90.000    TOP
C617       2448.00     2309.00     270.000    BOT
C618       2028.94     2099.85     270.000    TOP
C619       6429.07     3812.89     180.000    TOP
C620       6476.23     3812.89     180.000    TOP
C621       6464.60     3908.20      90.000    TOP
C622       6875.00     3775.00      90.000    TOP
C623       6863.00     3683.00       0.000    TOP
C624       6837.81     3941.33     180.000    TOP
C625       6699.67     3961.81     270.000    TOP
C626       6765.31     3826.33       0.000    BOT
C627       7048.05     3254.02       0.000    TOP
C628       7231.04     3530.38      90.000    BOT
C629       7231.04     3450.38      90.000    BOT
C630       6963.05     3254.02       0.000    TOP
C635       6514.23     3236.24      90.000    TOP
C636       6514.23     3313.07      90.000    TOP
C637       6514.00     3390.00      90.000    TOP
C638       2577.20     3762.70     270.000    TOP
C639       2590.00     3757.50      90.000    BOT
C640       2755.00     4075.00       0.000    TOP
C641       2530.00     4150.00     270.000    BOT
C642       2790.00     4075.00     180.000    TOP
C643       6514.00     3467.00      90.000    TOP
C644       6466.00     3684.00       0.000    TOP
C645       6469.00     3649.00      90.000    BOT
C646        598.00     1859.00     180.000    TOP
C647        331.00     2119.00     270.000    TOP
C648        736.00     2210.00     270.000    TOP
C649        813.00     1850.00       0.000    TOP
C650        684.00     1849.00       0.000    TOP
C651        858.00     2094.00      90.000    TOP
C652        858.00     1994.00      90.000    TOP
C653        826.00     2255.00     180.000    TOP
C655        344.49     1915.48     270.000    TOP
C656       2325.00     3842.00     270.000    TOP
C657       6514.00     3544.00      90.000    TOP
C658       6522.00     3683.00       0.000    TOP
C659       7231.04     3296.38      90.000    BOT
C660       7231.04     3385.38      90.000    BOT
C661       6905.00     3838.00     180.000    TOP
C662       6914.00     3929.00       0.000    TOP
C663       6957.00     3930.50     180.000    TOP
C664       6815.40     4224.60       0.000    TOP
C665       6752.00     3667.79     270.000    BOT
C666       1693.00     1709.00       0.000    TOP
C667       1613.00     1709.00       0.000    TOP
C668       1533.00     1709.00       0.000    TOP
C669       1644.00     1958.00     180.000    TOP
C670       1723.00     1958.00     180.000    TOP
C671       1567.00     1958.00     180.000    TOP
C672       1785.00     1960.00     180.000    TOP
C673       1733.00     1045.00      90.000    TOP
C674       5835.00     4495.00      90.000    BOT
C675       5690.70     4632.30     180.000    TOP
C676       5883.00     4904.00     270.000    TOP
C677       5364.00     3194.00      90.000    TOP
C678       5363.28     3116.98      90.000    TOP
C679       5363.28     3138.98      90.000    TOP
C680       5361.48     3042.21      90.000    TOP
C681       5361.48     3064.21      90.000    TOP
C682       5364.13     2966.80      90.000    TOP
C683       5364.13     2988.80      90.000    TOP
C684       2448.00     2081.00     270.000    BOT
C685       2448.00     2157.00     270.000    BOT
C686       7158.34     4834.00      90.000    TOP
C687       7158.34     4756.00      90.000    TOP
C688       7159.00     4679.00      90.000    TOP
C689       5184.00     4568.00     270.000    BOT
C690       5192.00     4624.00     270.000    BOT
C691       7364.00     4594.00     180.000    TOP
C692       7299.00     4639.00     270.000    TOP
C693       5375.00     4184.00     270.000    TOP
C694       5370.00     4315.00     270.000    TOP
C695       5370.00     4239.00     270.000    TOP
C696       6206.00     4367.00       0.000    TOP
C697       6158.70     4367.30       0.000    TOP
C698       6269.00     4374.00       0.000    TOP
C699       6269.00     4374.00       0.000    BOT
C700       6192.00     4374.00       0.000    BOT
C701       2322.00     3778.00     270.000    TOP
C702       2322.00     3701.00     270.000    TOP
C703       2200.00     4705.00     270.000    TOP
C704       2200.00     4785.00     270.000    TOP
C705       2200.00     4840.00     270.000    TOP
C706       6858.00     4743.66      90.000    BOT
C707       6858.00     4667.00      90.000    BOT
C708       2448.00     2233.00     270.000    BOT
C709       1689.38     4178.70     270.000    BOT
C710       5975.00     4345.00      90.000    TOP
C711       2262.00     4064.00       0.000    TOP
C712       1509.00     1365.00     270.000    TOP
C713       2590.00     4310.00      90.000    TOP
C714        858.00     2044.00      90.000    TOP
C715       7373.20     4279.80     270.000    TOP
C719       5810.00     3955.00     180.000    TOP
C720       5735.00     3960.00     180.000    TOP
C721       5560.00     4612.60     270.000    BOT
C730       2240.00      950.00      90.000    TOP
C731       3379.00     4260.00     180.000    TOP
C732        591.00     3910.50     270.000    TOP
C733        497.00     3964.00       0.000    TOP
C734       2435.00      950.00      90.000    TOP
C735       6449.50      385.00     180.000    BOT
C736        485.00     3875.00      90.000    TOP
C737        265.00     1585.00       0.000    TOP
C738        590.80     3993.90     270.000    TOP
C739        972.30     1218.20       0.000    TOP
C740       6560.51      449.93       0.000    BOT
C741       2239.95      684.91       0.000    TOP
C742       3307.08     4396.68     270.000    TOP
C743       2427.33      685.11       0.000    TOP
C744       6672.83     3470.18     270.000    TOP
CN1        1456.69      198.03       0.000    TOP
CN2        3385.83      149.61       0.000    TOP
CN6        7086.61      149.61       0.000    TOP
D2         7396.80     4336.40     180.000    BOT
D3         5624.60     4665.70     180.000    TOP
D37         766.00     1273.00     180.000    TOP
DB1        1181.10     4724.41     180.000    TOP
DEBUG1     6144.00     4111.40       0.000    TOP
DEBUG2     7765.20     3443.00     180.000    TOP
G3         2710.18     3955.24     270.000    TOP
G5         6055.70     4742.30       0.000    TOP
L1         3522.30     2515.71       0.000    BOT
L2         3522.28     2796.87       0.000    BOT
L3         3522.54     2656.41     180.000    BOT
L4         3522.22     2937.41     180.000    BOT
L5         3522.14     3077.62       0.000    BOT
L6         6350.00     4375.00     180.000    TOP
L7         2775.00     1475.00      90.000    BOT
L8         2775.00     2395.00      90.000    BOT
L9         2775.00     1980.00      90.000    BOT
L10        2775.00     2310.00      90.000    BOT
L11        2775.00     1475.00      90.000    TOP
L12        2775.00     2395.00      90.000    TOP
L13        2775.00     1980.00      90.000    TOP
L14        2775.00     1565.00      90.000    TOP
L15        2775.00     2310.00      90.000    TOP
L16        2775.00     1895.00      90.000    BOT
L17        2775.00     1565.00      90.000    BOT
L18        2775.00     1895.00      90.000    TOP
L19        6580.00     2630.00     180.000    BOT
L20        6055.26     2634.52     180.000    BOT
L21        6240.26     2634.52     180.000    BOT
L22        7985.07     1245.93      90.000    BOT
L23        6395.00     2630.00     180.000    BOT
L24        6253.00     1070.00       0.000    BOT
L25        7940.00     1125.00      90.000    BOT
L26        6882.00     3255.00       0.000    TOP
L27        7355.12     3937.15     180.000    TOP
L28        2433.00     3587.00     180.000    TOP
L29        5714.56     4415.31     270.000    TOP
L30        1336.00     1834.00       0.000    TOP
L31        2380.00     1805.00      90.000    TOP
L32        6524.31     3145.83     180.000    TOP
L33        6902.26     3477.71      90.000    TOP
L34        2368.20     4283.38     180.000    TOP
L35        5600.00     3960.00       0.000    TOP
LED1       7765.00      955.00     180.000    BOT
LED2       7900.00      955.00     180.000    BOT
LHOLE1      374.02     5174.41       0.000    TOP
MSAS1      4133.86     4606.30     180.000    TOP
P1          450.00     2052.00       0.000    BOT
PSP1       1932.64     1373.98       0.000    TOP
PSP2       6585.00     3700.00     180.000    BOT
Q2         3365.00     2929.80     270.000    TOP
Q3         7614.00      957.30     270.000    BOT
Q4         7995.00      970.00       0.000    BOT
Q5         7760.00      820.00       0.000    BOT
Q6         7955.00      785.00      90.000    BOT
Q7         1969.00     1830.00      90.000    TOP
Q8         6875.00     2785.00     180.000    BOT
Q9         5257.00     4851.00     270.000    BOT
Q10        5593.00     4849.00      90.000    BOT
Q11        6908.90     4152.70       0.000    TOP
Q12        7198.50     4337.20       0.000    TOP
Q13        5591.05     4705.40      90.000    BOT
Q14         319.00     2658.00      90.000    TOP
Q16        6730.00     2785.00       0.000    BOT
Q20        6565.00      670.00     180.000    TOP
Q22        7052.00     4243.60       0.000    TOP
Q23         417.00     1425.00     180.000    TOP
Q34        7340.40     4375.90       0.000    TOP
Q35        7237.12     4633.71      90.000    BOT
Q36        5403.12     4547.71     180.000    BOT
Q37         434.87     1705.31     180.000    TOP
R1         5439.95     4800.90      90.000    BOT
R2         5494.00     4876.90     180.000    BOT
R3         7337.42     4473.67      90.000    TOP
R4         5723.33     4764.88      90.000    BOT
R8         7269.70     4239.30     270.000    TOP
R9         7299.00     4754.00     270.000    TOP
R10        5184.50     4760.00     270.000    BOT
R11         641.00     1861.00     180.000    TOP
R12         419.38     2337.04     180.000    TOP
R13         459.38     2337.04     180.000    TOP
R14         632.00     1357.00      90.000    TOP
R15         857.00     1851.00       0.000    TOP
R16         768.00     1849.00       0.000    TOP
R17         858.00     2138.00     270.000    TOP
R18         873.00     1949.00     270.000    TOP
R19         913.00     2254.00       0.000    TOP
R20         858.00     2179.00      90.000    TOP
R22         873.00     1909.00      90.000    TOP
R24        5452.06     4128.82     180.000    TOP
R25        5867.20     4746.80     180.000    TOP
R26        5617.06     4128.82     180.000    TOP
R27        5827.70     4685.30     270.000    TOP
R28        6391.20     4551.30     180.000    BOT
R29        5733.00     4897.00      90.000    TOP
R31        6280.70     4684.30      90.000    TOP
R33        4759.00     3508.00      90.000    TOP
R34        3708.00     2880.00      90.000    TOP
R35        4112.50     3302.50      90.000    BOT
R36        5175.17     3435.46     180.000    BOT
R37        4560.41     3563.55     270.000    BOT
R38        4722.96     3425.00       0.000    TOP
R39        5220.00     3531.50     180.000    TOP
R40        4972.06     3435.31     180.000    BOT
R41        4961.00     3536.00     180.000    BOT
R42        5215.22     3435.46     180.000    BOT
R43        5135.17     3435.46     180.000    BOT
R44        4720.97     3586.38     270.000    TOP
R45        4525.41     3516.40     270.000    BOT
R46        4699.96     3527.12     180.000    TOP
R47        4215.00     3428.00     180.000    BOT
R48        5513.94     3334.88       0.000    TOP
R49        5479.08     3334.32       0.000    BOT
R50        5473.15     3334.88       0.000    TOP
R51        5417.47     3334.65       0.000    BOT
R52        5492.00     3531.00       0.000    BOT
R53        5452.00     3531.00       0.000    BOT
R54        5225.00     3540.00     180.000    BOT
R55        5185.00     3540.00     180.000    BOT
R56        5362.00     3531.00       0.000    BOT
R57        5402.00     3531.00       0.000    BOT
R58        5417.14     3335.03       0.000    TOP
R59        5339.47     3335.00       0.000    BOT
R60        5296.15     3316.79     270.000    TOP
R61        5353.36     3335.22       0.000    TOP
R62        5296.15     3356.79     270.000    TOP
R63        5299.47     3335.00       0.000    BOT
R64        5060.00     3533.00       0.000    BOT
R65        5100.00     3533.00       0.000    BOT
R66        5540.00     3500.00       0.000    BOT
R67        5580.00     3500.00       0.000    BOT
R68        5288.94     3493.15       0.000    TOP
R69        5328.94     3493.15       0.000    TOP
R70        5296.22     3435.46       0.000    BOT
R71        5255.22     3435.46       0.000    BOT
R72        3960.00     3424.00     180.000    BOT
R73        4003.00     3434.00     180.000    TOP
R74        4786.18     3411.42       0.000    BOT
R75        2507.91      674.27     180.000    TOP
R76        3239.00     2495.00       0.000    TOP
R77        3906.49     3405.63     270.000    TOP
R78        4826.18     3411.42     180.000    BOT
R79        3919.00     3424.00       0.000    BOT
R80        6643.01      335.65     180.000    TOP
R81        6330.00      640.00       0.000    BOT
R83        4765.00     3425.00       0.000    TOP
R84        6989.00     4834.00      90.000    TOP
R85        4134.00     3423.00       0.000    BOT
R86        4174.00     3423.00       0.000    BOT
R87        4168.41     3420.84       0.000    TOP
R88        2695.00     4185.00     180.000    TOP
R89        2760.00      290.00      90.000    TOP
R90        2760.00      380.00      90.000    TOP
R91        1618.00     1177.00     270.000    TOP
R92        6850.00     4333.00      90.000    TOP
R93        6841.00     4409.50      90.000    TOP
R94        3180.50     2949.00     180.000    TOP
R95        6679.00     4449.00     180.000    TOP
R96        2295.00      730.00      90.000    TOP
R97        3430.00     3040.00     180.000    TOP
R98        7163.50     4462.30      90.000    TOP
R99        7171.50     4519.95       0.000    TOP
R100       5127.54     3434.84     180.000    TOP
R101       5073.37     3435.63     180.000    TOP
R102       5027.00     3436.00     180.000    TOP
R103       4979.00     3436.00     180.000    TOP
R104       4329.00     3426.00       0.000    BOT
R105       2760.00      335.00      90.000    TOP
R106       3645.00     2930.00     270.000    TOP
R107       4215.00     3325.00     180.000    BOT
R108       3710.00     2755.00     270.000    TOP
R109       4384.86     3513.41      90.000    BOT
R110       5022.00     3623.09       0.000    BOT
R111       4275.00     3324.00     180.000    BOT
R112       3708.00     2839.00     270.000    TOP
R113       4932.00     3540.00       0.000    TOP
R114       4275.00     3423.00       0.000    BOT
R115       5002.00     1948.00      90.000    BOT
R116       4997.00     3540.00       0.000    TOP
R117       5140.00     3533.00       0.000    TOP
R118       5062.00     3540.00       0.000    TOP
R119       5180.00     3531.50       0.000    TOP
R120       4277.00     3423.00     180.000    TOP
R121       3485.97     2113.40       0.000    TOP
R122       3645.00     3032.00      90.000    TOP
R123       3645.00     2992.00      90.000    TOP
R124       3725.00     2992.00      90.000    TOP
R125       3725.00     3032.00      90.000    TOP
R126       4866.27     3566.74     180.000    TOP
R127       4914.45     3486.58     180.000    BOT
R128       4824.27     3566.74     180.000    TOP
R129       3451.21     3297.50     180.000    TOP
R130       3630.27     3126.54     270.000    TOP
R131       4807.00     3425.00     180.000    TOP
R132       3433.91     3197.17      90.000    TOP
R133       3709.32     3220.00     180.000    TOP
R134       5665.00     3955.00       0.000    TOP
R135       3733.98     3410.70     270.000    BOT
R136       4375.00     3425.00     180.000    TOP
R137       4352.00     3323.00     180.000    BOT
R138       4407.40     3429.44     180.000    BOT
R139       4454.00     3325.00       0.000    BOT
R140       4494.00     3325.00       0.000    BOT
R141       4513.00     3426.00     180.000    BOT
R142       4643.27     3425.01     180.000    TOP
R143       4600.00     3425.00     180.000    BOT
R144       4603.27     3425.01     180.000    TOP
R145       4502.00     3239.00       0.000    BOT
R146       4640.00     3425.00     180.000    BOT
R147       4514.00     3425.00     180.000    TOP
R148       3710.00     2795.00     270.000    TOP
R149       3167.86     3882.42       0.000    BOT
R150       3422.50     3098.23     270.000    TOP
R151       3582.98     2521.44     180.000    BOT
R152       3583.42     2802.87     180.000    BOT
R153       3581.69     2670.68       0.000    BOT
R154       3582.22     2943.41       0.000    BOT
R155       3582.14     3083.62     180.000    BOT
R156       4868.73     3486.56     180.000    BOT
R157       2780.00     1410.00      90.000    BOT
R158       2775.00     2460.00      90.000    BOT
R159       2780.00     2045.00      90.000    BOT
R160       2780.00     2245.00      90.000    BOT
R161       2780.00     1410.00      90.000    TOP
R162       2775.00     2460.00      90.000    TOP
R163       2780.00     2045.00      90.000    TOP
R164       2775.00     1830.00      90.000    TOP
R165       2775.00     1630.00      90.000    TOP
R166       2780.00     2245.00      90.000    TOP
R167       2775.00     1830.00      90.000    BOT
R168       2775.00     1630.00      90.000    BOT
R169       6393.92      884.36     180.000    TOP
R170       6376.92      942.36     270.000    TOP
R171       7643.00     1642.00      90.000    TOP
R172       7385.79     1558.99      90.000    BOT
R173       6451.92      942.36     270.000    TOP
R174       6434.92      884.36     180.000    TOP
R175       7529.68     1640.81     270.000    TOP
R176       7385.79     1518.99     270.000    BOT
R177       6240.00     1625.00      90.000    TOP
R178       6435.00     1660.00     270.000    BOT
R179       7521.08     1541.00     270.000    TOP
R180       7553.18     1790.53     270.000    TOP
R181       7602.00     1354.00     270.000    TOP
R182       7560.00     1608.00     270.000    BOT
R183       7553.00     1695.50     270.000    TOP
R184       7591.50     1395.00     270.000    TOP
R185       7557.21     1450.50     270.000    BOT
R186       7865.00     1391.00     180.000    BOT
R187       7588.15     1404.33     270.000    BOT
R188       7555.00     1695.00     270.000    BOT
R189       7591.71     1436.24     270.000    TOP
R190       7588.15     1363.83     270.000    BOT
R191       7359.52     1603.15     270.000    BOT
R192       6280.00     2050.00       0.000    BOT
R193       7961.10     1846.00     180.000    BOT
R194       6240.00     2050.00       0.000    BOT
R195       6440.00     2050.00       0.000    BOT
R196       6520.00     2050.00       0.000    BOT
R197       6480.00     2050.00       0.000    BOT
R198       7985.00     1391.00       0.000    BOT
R199       7825.00     1391.00       0.000    BOT
R200       6320.00     2050.00       0.000    BOT
R201       7945.00     1391.00       0.000    BOT
R202       7894.50     1828.50     270.000    BOT
R203       6360.00     2050.00       0.000    BOT
R204       6400.00     2050.00       0.000    BOT
R205       7815.41     1828.31     270.000    BOT
R206       4782.98     3565.54     180.000    TOP
R207       3784.84     3108.47     270.000    BOT
R208       7905.00     1391.00     180.000    BOT
R209       8026.96     1391.00     180.000    BOT
R210       4680.00     3425.00     180.000    BOT
R211       6640.00      555.00     180.000    TOP
R212       5095.17     3435.46       0.000    BOT
R213       7257.50     2192.72       0.000    TOP
R214       7387.86     2302.23       0.000    TOP
R215       7553.30     2062.00     270.000    TOP
R216       7553.18     1872.53     270.000    TOP
R217       7553.18     1831.53     270.000    TOP
R218       7197.00     2163.00       0.000    BOT
R219       7127.20     2361.22       0.000    TOP
R220       6985.41     2008.89     180.000    BOT
R221       7193.00     2192.00     180.000    TOP
R222       7266.56     2301.98     180.000    TOP
R223       7342.86     2227.23     180.000    TOP
R224       7395.00     2227.00     180.000    TOP
R225       7553.30     2102.00      90.000    TOP
R226       7436.00     2227.00     180.000    TOP
R227       7553.30     2142.00      90.000    TOP
R228       7553.30     2017.00      90.000    TOP
R229       7135.00     2175.00     270.000    TOP
R230       8019.34     2894.46       0.000    TOP
R231       7143.46     2765.58      90.000    BOT
R232       6810.84     2015.45     270.000    BOT
R233       7588.15     1321.81     270.000    BOT
R234       7368.00      979.00     270.000    BOT
R235       7302.31      982.93     270.000    TOP
R236       5012.81     3435.11       0.000    BOT
R237       7553.02     1737.15     270.000    TOP
R238       7810.00      935.00     180.000    BOT
R239       7853.50      935.00     180.000    BOT
R240       6323.00     1564.00     180.000    BOT
R241       7608.70      861.00      90.000    BOT
R242       7608.70      819.00      90.000    BOT
R243       7608.40      778.10      90.000    BOT
R244       7853.50      860.00       0.000    BOT
R245       2760.00      425.00      90.000    TOP
R246       2830.00     2880.00       0.000    BOT
R247       6911.00     2355.00       0.000    TOP
R248       7452.00      904.00     270.000    TOP
R249       7510.23      918.15     180.000    TOP
R250       7452.00      863.00     270.000    TOP
R251       7135.00     1369.50       0.000    BOT
R252       6785.00     2355.00       0.000    TOP
R253       6869.00     2355.00       0.000    TOP
R254       7521.23     1482.45     270.000    TOP
R255       6560.13     1669.29      90.000    BOT
R256       7521.00     1600.50     270.000    TOP
R257       7175.00     1369.50       0.000    BOT
R258       7452.00      945.00     270.000    TOP
R259       7555.23      918.15     180.000    TOP
R260       6459.68     2287.97       0.000    TOP
R261       6600.00     2050.00       0.000    BOT
R262       6502.87     2287.74       0.000    TOP
R263       6544.64     2288.15       0.000    TOP
R264       6631.10     2286.75       0.000    TOP
R265       6586.10     2286.75       0.000    TOP
R266       6415.79     2288.90       0.000    TOP
R267       6673.53     2286.32       0.000    TOP
R268       6560.00     2050.00       0.000    BOT
R269       6956.00     2355.00     180.000    TOP
R270       7377.00      903.00     270.000    TOP
R271       7527.00      978.00      90.000    TOP
R272       7377.00      862.00     270.000    TOP
R273       7077.47     1384.06     270.000    BOT
R274       6996.00     2355.00     180.000    TOP
R275       6827.00     2355.00     180.000    TOP
R276       7319.00      903.00       0.000    TOP
R277       6520.00     2629.00       0.000    BOT
R278       6115.26     2632.52       0.000    BOT
R279       6180.26     2632.52       0.000    BOT
R280       7985.07     1305.93     270.000    BOT
R281       6455.00     2629.00       0.000    BOT
R282       6315.00     1070.00     180.000    BOT
R283       7935.00     1065.00     270.000    BOT
R284       6819.00     3246.00       0.000    TOP
R285       7158.00     3846.00     180.000    TOP
R286       6288.28     3644.24      90.000    TOP
R287       2875.00     2880.00     180.000    BOT
R288       6918.87     2661.77     180.000    BOT
R289       5994.23     3527.29     270.000    TOP
R290       5994.23     3567.29     270.000    TOP
R291       6288.28     3853.04      90.000    TOP
R292       5993.40     3952.20      90.000    TOP
R293       6106.50     3952.20      90.000    TOP
R294       5990.73     3789.55     270.000    TOP
R295       5990.73     3749.55     270.000    TOP
R296       7737.36     2931.80      90.000    TOP
R297       7596.51     2651.07     180.000    TOP
R298       7816.40     2931.80      90.000    TOP
R299       7638.40     2650.10     180.000    TOP
R300       7920.00     2310.00     180.000    BOT
R301       5053.79     3435.11       0.000    BOT
R302       4774.00     3526.00     180.000    BOT
R303       6712.00     2880.00      90.000    BOT
R304       7965.00     2310.00       0.000    BOT
R305       3600.00     3405.00     270.000    TOP
R306       3725.00     3445.00     270.000    TOP
R307       4883.44     3548.73      90.000    BOT
R308       4800.00     3668.00      90.000    TOP
R309       3726.82     3285.03     270.000    TOP
R310       3793.83     3148.95      90.000    BOT
R311       6170.00     4745.00       0.000    TOP
R312       6410.03      640.09       0.000    BOT
R313       6370.03      640.09     180.000    BOT
R314       6187.67     3748.94     270.000    TOP
R315       6187.67     3788.94     270.000    TOP
R316       6293.70     4583.30     180.000    TOP
R317       6804.89     2685.00      90.000    BOT
R320       6215.00     4745.00       0.000    TOP
R321       5903.50     3287.50     180.000    TOP
R322       6189.00     3211.00     180.000    TOP
R323       6318.00     3210.00     180.000    TOP
R324       6276.23     4778.31      90.000    TOP
R325       6132.11     2819.05       0.000    TOP
R326       6022.87     3224.56     270.000    TOP
R327       6022.87     3266.56     270.000    TOP
R328       6087.11     2819.05       0.000    TOP
R329       6240.50     3489.00     270.000    TOP
R330       6215.50     3534.00     270.000    TOP
R331       6240.50     3104.91     270.000    TOP
R332       6215.50     3149.91     270.000    TOP
R333       6140.50     3534.00     270.000    TOP
R334       6135.50     3149.91     270.000    TOP
R335        290.00     3230.00      90.000    TOP
R336        290.00     3095.00      90.000    TOP
R337        272.00     3035.00     180.000    TOP
R341        755.00     3140.00      90.000    TOP
R344        290.00     3185.00     270.000    TOP
R345        290.00     3140.00     270.000    TOP
R346        314.00     3035.00       0.000    TOP
R347        757.00     3095.00      90.000    TOP
R348       2981.35     1041.77     270.000    TOP
R350       4968.00     3683.50      90.000    BOT
R351        757.00     3045.00      90.000    TOP
R352       5990.37     2800.17      90.000    TOP
R353       6235.00     2787.45      90.000    TOP
R354        757.96     2816.95      90.000    TOP
R355        757.96     2766.95      90.000    TOP
R356        757.96     2866.95      90.000    TOP
R357        287.00     2832.00      90.000    TOP
R358        287.00     2967.00      90.000    TOP
R359       6310.00     2787.45     270.000    TOP
R360        287.00     2922.00     270.000    TOP
R361        266.00     2772.00     180.000    TOP
R362        307.00     2772.00       0.000    TOP
R363        287.00     2877.00     270.000    TOP
R364       7469.70     3090.20       0.000    TOP
R365       7514.70     3090.20     180.000    TOP
R366       7964.70     3071.20     270.000    TOP
R367       7964.70     3026.20     270.000    TOP
R368       7558.83     3216.84      90.000    TOP
R369       7558.83     3171.84     270.000    TOP
R370       7489.70     3016.20      90.000    TOP
R371       7489.70     2971.20     270.000    TOP
R372       5827.00     4603.00     270.000    TOP
R373       5927.00     4791.00      90.000    TOP
R374       6547.70     3963.60       0.000    TOP
R375       4720.00     3525.00     180.000    BOT
R376       6706.10     4171.30     180.000    TOP
R377       5883.00     4866.50     270.000    TOP
R378       5735.70     4619.80     180.000    TOP
R379       6060.00     4350.00     180.000    TOP
R380       4009.58     2629.52      90.000    BOT
R381       5815.00     4620.00       0.000    BOT
R382       5532.06     4128.82     180.000    TOP
R383       1567.00     1345.00     180.000    TOP
R386       1618.00     1090.50      90.000    TOP
R387       5936.90     4304.40      90.000    TOP
R393       4559.00     3425.00       0.000    BOT
R394       7108.00     2163.00       0.000    BOT
R395       7307.12     2302.07       0.000    TOP
R396       7553.30     1972.00     270.000    TOP
R397       1618.00     1134.00     270.000    TOP
R398       1718.00     1145.00      90.000    TOP
R399       1778.00     1100.00      90.000    TOP
R400       1583.00     1220.00     270.000    TOP
R401       1951.61     1298.17     180.000    TOP
R402       6917.50     2364.69     270.000    BOT
R403       4124.00     3420.84     180.000    TOP
R404       4745.77     3411.65     180.000    BOT
R405       4473.00     3426.00       0.000    BOT
R406       1622.70     1043.10      90.000    TOP
R407        731.00     3738.00     180.000    TOP
R408        813.00     3688.00       0.000    TOP
R409        772.00     3688.00       0.000    TOP
R410        670.50     3677.51      90.000    TOP
R411        655.00     3738.00     180.000    TOP
R412        299.00     3733.52     180.000    TOP
R413        382.00     3686.00       0.000    TOP
R414        341.00     3686.00       0.000    TOP
R415        243.50     3675.52      90.000    TOP
R416        857.95     3734.26     180.000    TOP
R417       2520.00     2862.00       0.000    TOP
R418       2389.00     2862.00     180.000    TOP
R419       2458.00     2863.00     180.000    TOP
R420       2307.00     2862.00       0.000    TOP
R421       2194.00     2857.00     180.000    TOP
R422       2266.00     2862.00     180.000    TOP
R423       2560.00     2862.00       0.000    TOP
R424       2348.00     2861.00       0.000    TOP
R425        220.00     3733.52     180.000    TOP
R426        430.00     3732.33     180.000    TOP
R427       2716.00     2862.00       0.000    TOP
R428       2600.00     2862.00     180.000    TOP
R429       2676.00     2862.00     180.000    TOP
R430        507.00     3732.33     180.000    TOP
R431        604.00     3684.00       0.000    TOP
R432        548.00     3684.00       0.000    TOP
R433       2756.00     2862.00       0.000    TOP
R434        454.00     3674.00      90.000    TOP
R435        324.05     1860.17       0.000    TOP
R436        364.05     1860.17       0.000    TOP
R437       2402.00     3051.00     180.000    TOP
R438       2587.00     3026.00     180.000    TOP
R439       2852.41     2785.76      90.000    TOP
R440       1698.00     1470.00       0.000    TOP
R441       2220.00     3050.00     180.000    TOP
R442       7828.00     3264.70     180.000    TOP
R443       6863.90     4265.70       0.000    TOP
R444       6953.80     4265.50       0.000    TOP
R445       5955.00     3469.50     270.000    TOP
R446        881.45     3676.26      90.000    TOP
R448        982.95     3685.93       0.000    TOP
R449        936.95     3734.26     180.000    TOP
R450       1023.95     3685.93       0.000    TOP
R455       4473.00     3425.00       0.000    TOP
R461       3515.00     3080.00     270.000    TOP
R470       2095.00     2840.00     270.000    TOP
R471       2020.00     2988.00      90.000    TOP
R472       2020.00     3068.00      90.000    TOP
R473       2153.00     2857.00       0.000    TOP
R474       1951.13     1146.44      90.000    TOP
R475       4216.79     2638.35     270.000    BOT
R476       4310.89     2672.40      90.000    BOT
R477       1853.00     1100.00      90.000    TOP
R478       2011.39     1163.95     180.000    TOP
R479       2105.00     2026.00     180.000    TOP
R480       2081.00     1649.00       0.000    TOP
R481       1765.00     1726.00     180.000    TOP
R482       1916.57     1531.96      90.000    TOP
R483       6615.31     3783.83     180.000    BOT
R484       6660.31     3783.83     180.000    BOT
R485       6570.31     3783.83     180.000    BOT
R486       6477.20     3953.00     270.000    TOP
R487        279.00     2235.00      90.000    TOP
R488       7231.04     3335.38     270.000    BOT
R489       7002.00     3800.00     180.000    TOP
R490       6951.00     3800.00     180.000    TOP
R491       7002.00     3930.00       0.000    TOP
R492       6875.81     3941.33       0.000    TOP
R493       6666.81     4001.83      90.000    TOP
R494       6699.31     3924.33     270.000    TOP
R495       6758.31     3943.33     180.000    TOP
R496       6721.31     3848.83       0.000    BOT
R497       6865.00     2102.00      90.000    BOT
R498       6940.00     2102.00     270.000    BOT
R499       2543.00     3665.00       0.000    BOT
R500       2615.00     4203.00      90.000    TOP
R501       2615.00     4121.00      90.000    TOP
R502       2723.68     3822.00     270.000    TOP
R503       2561.91     3718.27      90.000    TOP
R504       2723.68     3782.00     270.000    TOP
R505       2764.69     3734.25     270.000    TOP
R508       2652.50     3724.50       0.000    TOP
R509       2391.25     4850.61       0.000    TOP
R510       2311.25     4850.61       0.000    TOP
R511       2471.25     4850.61       0.000    TOP
R512       2831.00     4214.00       0.000    TOP
R513       2830.00     4075.00     180.000    TOP
R514       2577.50     4265.00      90.000    TOP
R515       2626.00     4139.00     180.000    BOT
R516       2305.00     3949.54      90.000    TOP
R517       2555.00     4175.00     180.000    TOP
R518       2790.00     4000.00       0.000    TOP
R519        566.07     1700.52     180.000    TOP
R520        526.07     1700.52     180.000    TOP
R521        873.00     2254.00     180.000    TOP
R522        505.00     1852.00     180.000    TOP
R523        465.00     1852.00     180.000    TOP
R524        655.00     2328.00     180.000    TOP
R525        293.00     1655.00      90.000    TOP
R526        330.00     1555.00     180.000    TOP
R527        293.00     1715.00      90.000    TOP
R528        591.00     4031.50     270.000    TOP
R529       2947.08     2938.26       0.000    TOP
R531        548.00     1520.00     270.000    TOP
R532        259.00     2053.00     180.000    TOP
R533        896.00     3929.00     180.000    TOP
R534        257.00     3977.00       0.000    TOP
R535       6588.40     3963.60       0.000    TOP
R536        755.00     2328.00       0.000    TOP
R538       7434.80     4338.90       0.000    TOP
R539       5682.39     4612.61      90.000    BOT
R540       2997.10     2811.22      90.000    TOP
R541       2802.06     2974.34      90.000    TOP
R542       2872.14     2899.17       0.000    TOP
R543        299.00     2053.00       0.000    TOP
R544       2320.00      680.00      90.000    TOP
R545       3283.38     4050.44     270.000    TOP
R546       6894.68     2484.05     180.000    BOT
R547       6804.89     2628.54     270.000    BOT
R548        279.00     2275.00      90.000    TOP
R549       3434.00     3239.00      90.000    TOP
R550        728.00     1849.00     180.000    TOP
R551        898.00     1851.00     180.000    TOP
R552       3305.31     4108.61       0.000    TOP
R553       3260.83     4108.66     180.000    TOP
R555       3306.86     4435.10      90.000    TOP
R556       3721.19     2595.80       0.000    TOP
R557       4800.00     3718.00     270.000    BOT
R558        937.00     3929.00       0.000    TOP
R559       4801.00     3675.00      90.000    BOT
R560       4801.00     3634.00      90.000    BOT
R561       3725.00     3405.00      90.000    TOP
R562       3840.00     3427.50       0.000    TOP
R563       4848.44     3591.95     270.000    BOT
R564       4800.00     3624.00      90.000    TOP
R565       4679.00     3525.00     180.000    BOT
R566       3999.30     3314.30     270.000    BOT
R567       4091.00     3423.00     180.000    BOT
R569       4097.20     3356.30      90.000    BOT
R572        257.00     3902.00       0.000    TOP
R573       2854.00     3191.00     180.000    TOP
R574       2570.00      900.00     270.000    TOP
R575       2388.80      685.62     180.000    TOP
R576       2465.30      685.36       0.000    TOP
R577       6598.50      485.00       0.000    BOT
R578       6447.10      245.67     180.000    BOT
R579        705.00     2328.00       0.000    TOP
R580       4322.14     3563.73      90.000    TOP
R581       3653.87     2597.09       0.000    TOP
R582       2570.00      950.00     270.000    TOP
R583       2932.00     3217.00      90.000    TOP
R584       2790.00     3216.00     270.000    TOP
R585        375.00     3857.00       0.000    TOP
R587       2202.27      685.15     180.000    TOP
R599       5758.00     4834.00     270.000    BOT
R601       5758.00     4879.00     270.000    BOT
R602       5259.50     4760.00     270.000    BOT
R603       7061.20     4362.30       0.000    TOP
R604       7102.00     4362.30       0.000    TOP
R605       6745.00     4075.00     270.000    TOP
R606       7260.90     4474.30      90.000    TOP
R607       6753.80     4561.60     180.000    TOP
R608        432.00     2619.00      90.000    TOP
R609        432.00     2661.00     270.000    TOP
R688        337.00     2252.00       0.000    TOP
R691        635.67     2423.33     270.000    TOP
R692        565.41     2327.86       0.000    TOP
R693        524.00     2328.00       0.000    TOP
R694       6676.17     3559.67       0.000    TOP
RHOLE1     7893.70     5174.41       0.000    TOP
TC1        2471.00     2135.00     270.000    TOP
TC2        2471.50     2386.00     270.000    TOP
TC3        2479.00     1475.00     270.000    TOP
TC4        2240.00     4565.00     270.000    TOP
TC5        5330.00     4455.00     270.000    TOP
TC6        7288.93     3559.42      90.000    TOP
TC7        7288.93     3308.92      90.000    TOP
TP15       5161.94     3325.72       0.000    BOT
TP16       5245.00     3355.00       0.000    BOT
TP17       5289.02     3417.25       0.000    TOP
TP18       5236.02     3457.79       0.000    TOP
TP19       4271.66     2972.45       0.000    BOT
TP20       5575.00     3433.50       0.000    BOT
TP21       4908.00     4434.20       0.000    TOP
TP22       4855.00     4434.20       0.000    TOP
TP23       4855.00     4381.20       0.000    TOP
TP24       4908.00     4381.20       0.000    TOP
TP25       4665.35     3051.18       0.000    BOT
TP26       4232.28     3051.18       0.000    BOT
TP27       4726.00     3104.00       0.000    BOT
TP28       3716.48     3350.23       0.000    BOT
TP35       5180.20     3436.32       0.000    TOP
TP36       5034.68     3243.25       0.000    BOT
TP37       4311.02     2933.07       0.000    BOT
TP38       4311.02     3011.81       0.000    BOT
TP39       4213.57     3412.01       0.000    TOP
TP40       4213.75     3465.52       0.000    TOP
TP41       4232.29     3208.67       0.000    BOT
TP42       4311.05     3090.10       0.000    BOT
TP43       4192.91     3090.55       0.000    BOT
TP44       4932.00     3477.00       0.000    TOP
TP45       4559.00     3411.00       0.000    TOP
TP46       4429.08     2932.98       0.000    BOT
TP47       4429.13     3051.18       0.000    BOT
TP48       4389.76     3011.81       0.000    BOT
TP49       4389.76     3090.55       0.000    BOT
TP50       4653.00     3514.81       0.000    TOP
TP51       4340.00     3222.00       0.000    BOT
TP52       4322.00     3415.00       0.000    TOP
TP53       7604.50     1195.50     270.000    TOP
TP54       7256.00     1036.00      90.000    BOT
TP55       7083.00     1133.00      90.000    BOT
TP56       7151.00     1073.00      90.000    BOT
TP57       7190.00     1127.00      90.000    BOT
TP58       6957.70     1254.29      90.000    BOT
TP59       7540.00     1096.00     270.000    TOP
TP60       7242.00     1107.00      90.000    BOT
TP61       7540.00     1262.50     270.000    TOP
TP62       7457.00     1087.00      90.000    BOT
TP63       7399.00     1125.00      90.000    BOT
TP64       7635.00     1150.00     270.000    TOP
TP65       7427.00     1031.00      90.000    BOT
TP66       7195.00     1029.00      90.000    BOT
TP67       7302.00      982.00      90.000    BOT
TP68       7553.00     1311.50     270.000    TOP
TP69       7442.22     1205.27      90.000    BOT
TP70       7472.00     1274.00      90.000    BOT
TP71       7655.00     1195.00     270.000    TOP
TP72       7371.00     1030.00      90.000    BOT
TP73       7345.00     1134.00      90.000    BOT
TP74       7477.00     1148.00      90.000    BOT
TP75       7485.00     1097.50     270.000    TOP
TP76       7492.00     1262.50     270.000    TOP
TP77       7415.00     1465.00      90.000    BOT
TP78       7382.00     1176.00      90.000    BOT
TP79       6264.00     1985.00       0.000    BOT
TP80       7336.00     1205.00      90.000    BOT
TP81       6568.78     1610.79       0.000    BOT
TP82       7368.00     1252.00      90.000    BOT
TP83       6460.00     1859.00       0.000    BOT
TP84       7427.00     1306.00      90.000    BOT
TP85       6507.22     1834.39       0.000    BOT
TP86       7333.72     1302.35      90.000    BOT
TP87       7649.00     1308.00     270.000    TOP
TP88       6317.00     1985.00       0.000    BOT
TP89       7605.00     1260.00     270.000    TOP
TP90       6460.04     1797.68       0.000    BOT
TP91       7367.30     1665.22      90.000    BOT
TP92       6370.00     1985.00       0.000    BOT
TP93       7464.00     1346.00      90.000    BOT
TP94       6423.00     1985.00       0.000    BOT
TP95       7380.00     1339.00      90.000    BOT
TP96       7434.00     1391.00      90.000    BOT
TP97       6509.36     1608.74       0.000    BOT
TP98       7345.00     1392.00      90.000    BOT
TP99       7601.00     1309.00     270.000    TOP
TP100      7335.00     1460.00      90.000    BOT
TP101      7658.00     1258.00     270.000    TOP
TP102      7153.00     2144.00     270.000    BOT
TP103      7486.44     1910.51      90.000    TOP
TP104      7429.78     2062.02     270.000    BOT
TP105      7457.78     1782.04     270.000    BOT
TP106      7340.43     1872.31     270.000    BOT
TP107      7466.91     1895.52     270.000    BOT
TP108      7456.59     1837.88     270.000    BOT
TP109      7337.92     1753.76     270.000    BOT
TP110      7360.78     1817.64     270.000    BOT
TP111      7260.32     2059.04     270.000    BOT
TP112      7106.87     2025.64     270.000    BOT
TP113      7215.00     2026.00     270.000    BOT
TP114      7070.00     2175.00      90.000    TOP
TP115      7294.00     1118.00       0.000    BOT
TP116      7036.00     1106.00       0.000    BOT
TP117      7525.00     1275.00       0.000    BOT
TP118      6517.22     1985.88       0.000    BOT
TP119      6671.66     2171.94       0.000    TOP
TP120      6415.79     2217.70       0.000    TOP
TP121      6579.20     2215.60       0.000    TOP
TP122      6644.52     2223.15       0.000    TOP
TP123      6614.52     2172.41       0.000    TOP
TP124      6544.64     2173.58       0.000    TOP
TP125      6506.84     2216.30       0.000    TOP
TP126      6571.13     1984.15       0.000    BOT
TP127      6715.08     2208.24       0.000    TOP
TP128      6463.18     2177.78       0.000    TOP
TP129      7170.87      973.84       0.000    BOT
TP130      7371.00      956.00       0.000    TOP
TP131      7590.23      974.40       0.000    TOP
TP132      7078.61     1339.30       0.000    BOT
TP133      7260.39      849.55       0.000    TOP
TP134      6902.07     2055.97       0.000    BOT
TP135      7015.00     2190.00       0.000    TOP
TP136      6917.21     2233.00       0.000    TOP
TP137      6940.87     2017.24       0.000    BOT
TP138      6827.00     2233.00       0.000    TOP
TP139      6869.00     2275.00       0.000    TOP
TP140      6956.00     2275.00       0.000    TOP
TP141      6480.35     1543.30       0.000    BOT
TP142      6785.00     2275.00       0.000    TOP
TP143      7015.00     2255.00       0.000    TOP
TP144      7277.00     1180.00       0.000    BOT
TP145      7246.00      971.00       0.000    BOT
TP146      7137.00     1125.00       0.000    BOT
TP147      6936.74     1322.95       0.000    BOT
TP148      7504.00     1310.50       0.000    TOP
TP149      6999.99     1324.27       0.000    BOT
TP150      7160.40     1763.22       0.000    BOT
TP151      4855.00     4328.20       0.000    TOP
TP152      4908.00     4328.20       0.000    TOP
TP153      4855.00     4275.20       0.000    TOP
TP154      6752.64     2169.82       0.000    TOP
TP157      4685.00     3335.00       0.000    BOT
TP158      5014.00     3360.00       0.000    BOT
TP159      5067.00     3362.00       0.000    BOT
TP160      4960.00     3360.00       0.000    BOT
TP161      4975.50     3241.50       0.000    BOT
TP163      4192.92     2972.45       0.000    BOT
TP164      3535.56     2571.43       0.000    TOP
TP165      3535.00     2625.00       0.000    TOP
TP166      7730.00     3158.00       0.000    TOP
TP167      4908.00     4275.20       0.000    TOP
TP168      4232.21     2933.00       0.000    BOT
TP169      5521.00     3433.00       0.000    BOT
U1         4527.56     2637.80       0.000    TOP
U2         6889.76     1574.80       0.000    TOP
U4         6945.12     4572.71       0.000    TOP
U5          549.00     2097.00     270.000    TOP
U6         6679.53     3741.57      90.000    TOP
U7         1620.38     4431.36       0.000    BOT
U8         1778.00     1315.00     180.000    TOP
U9         6730.54     4287.06       0.000    TOP
U10        2518.70     3956.70       0.000    TOP
U11        6044.00     4561.00      90.000    TOP
U12        6428.76      363.68     180.000    TOP
U13        3170.00     3355.00     180.000    BOT
U14        2722.02      666.50      90.000    TOP
U15        7925.00     1620.00       0.000    BOT
U16        6787.39     2503.84     180.000    BOT
U18        7622.30     2648.71     270.000    BOT
U20        6096.20     3647.70     270.000    TOP
U21        6096.20     3871.50     270.000    TOP
U22        7669.37     2811.49      90.000    TOP
U23        3548.00     3252.00       0.000    BOT
U24        3337.50     2701.66     270.000    TOP
U25        6131.70     3376.98     270.000    TOP
U26        6131.70     2992.89     270.000    TOP
U27         524.04     3124.22     270.000    TOP
U29         525.00     2847.00     270.000    TOP
U30        7731.08     3049.51      90.000    TOP
U35         750.05     3508.07       0.000    TOP
U36         323.05     3506.07       0.000    TOP
U37        2310.32     3051.05     180.000    TOP
U38        2493.75     3050.67     180.000    TOP
U39        2687.97     3053.56     180.000    TOP
U40         533.05     3504.07       0.000    TOP
U41        2128.00     3051.00     180.000    TOP
U42        3686.00     3250.00       0.000    BOT
U46         961.00     3506.00       0.000    TOP
U47        2261.09      846.49     180.000    TOP
U48        3299.25     4259.11       0.000    TOP
U49        2456.09      846.49     180.000    TOP
U50        6548.66      341.00     270.000    BOT
U118       2949.38     3076.39     180.000    TOP
U119        740.07     3953.95     270.000    TOP
U120        401.00     3960.00      90.000    TOP
U122       2819.38     3076.39     180.000    TOP
VIA1       6540.37      929.58      90.000    TOP
VIA2       6620.47      927.89      90.000    TOP
VIA3       6701.46      927.55      90.000    TOP
VIA4       6782.25      927.46      90.000    TOP
VIA5       6862.79      927.44      90.000    TOP
VIA6       6943.65      927.08      90.000    TOP
VIA7       7023.91      927.60      90.000    TOP
VIA8       7103.78      946.49      90.000    TOP
VIA9       4908.77     1827.97      90.000    TOP
VIA10      5003.02     1827.39      90.000    TOP
VIA11      5104.27     1826.81      90.000    TOP
VIA12      5205.52     1826.23      90.000    TOP
VIA13      5512.50     2319.00       0.000    TOP
VIA14      5496.15     2406.38       0.000    TOP
VIA15      5487.25     2482.09       0.000    TOP
VIA16      5484.67     2557.96       0.000    TOP
VIA17      5764.00     1295.82     282.000    TOP
VIA18      5876.02     1404.21     282.000    TOP
VIA19      5949.34     1517.80     282.000    TOP
VIA20      5856.13     1606.08     282.000    TOP
VIA21      5892.38     1762.32     282.000    TOP
VIA22      5804.17     1850.60     282.000    TOP
VIA23      5845.42     2006.84     282.000    TOP
VIA24      5886.67     2163.08     282.000    TOP
VIA25      5474.43     3012.80     180.000    TOP
VIA26      5474.71     3087.71     180.000    TOP
VIA27      5475.28     3157.38     180.000    TOP
VIA28      5488.77     3240.49     180.000    TOP
X1         3387.29     2175.12       0.000    TOP
X2         6255.15     1764.71     270.000    TOP

EOS

#From(Function(Sicard.Report) Version 3.0)